FILE_TYPE = MACRO_DRAWING;
SET COLOR_WIRE YELLOW;
SET COLOR_PROP MONO;
SET COLOR_DOT WHITE;
SET COLOR_ARC YELLOW;
SET COLOR_BODY GREEN;
SET COLOR_NOTE MONO;
SET PROP_DISPLAY VALUE;
SET PAGE_NUMBER P209;
FORCEADD OFFPAGE..1
(-7625 1575);
FORCEPROP 2 LAST $XR0 206 
J 0
(-7877 1575);
DISPLAY 0.638298 (-7877 1575);
PAINT MONO (-7877 1575);
FORCEPROP 2 LAST CDS_LIB mstr_standard
J 0
(-7625 1575);
PAINT ORANGE (-7625 1575);
DISPLAY INVISIBLE (-7625 1575);
FORCEPROP 2 LAST PATH I1
J 0
(-7860 1610);
DISPLAY 1.021277 (-7860 1610);
PAINT ORANGE (-7860 1610);
DISPLAY INVISIBLE (-7860 1610);
FORCEPROP 2 LAST BOM_COST PROC_VRD_VCCIN_CPU0
J 0
(-7825 1625);
PAINT MONO (-7825 1625);
DISPLAY INVISIBLE (-7825 1625);
FORCEPROP 2 LAST ROOM PVCCIN_CPU1_VSENSE_VR
J 0
(-8150 1650);
PAINT ORANGE (-8150 1650);
DISPLAY INVISIBLE (-8150 1650);
FORCEPROP 1 LAST OFFPAGE TRUE
J 0
(-7300 1450);
DISPLAY 0.893617 (-7300 1450);
PAINT GREEN (-7300 1450);
DISPLAY INVISIBLE (-7300 1450);
FORCEPROP 1 LAST COMMENT_BODY TRUE
J 0
(-7500 1475);
DISPLAY 0.893617 (-7500 1475);
PAINT GREEN (-7500 1475);
DISPLAY INVISIBLE (-7500 1475);
FORCEADD RES..1
(-5475 1450);
FORCEPROP 1 LAST MATERIAL CHIP
J 0
(-5475 1300);
DISPLAY 0.617021 (-5475 1300);
PAINT SKYBLUE (-5475 1300);
FORCEPROP 1 LAST WATTAGE 1/16W
J 2
(-5500 1300);
DISPLAY 0.617021 (-5500 1300);
PAINT SKYBLUE (-5500 1300);
FORCEPROP 1 LAST PART_NUMBER G21497-005
J 0
(-5600 1550);
DISPLAY 0.617021 (-5600 1550);
PAINT BLUE (-5600 1550);
FORCEPROP 1 LASTPIN (-5375 1450) $PN 2
J 0
(-5413 1462);
DISPLAY 0.617021 (-5413 1462);
PAINT GREEN (-5413 1462);
FORCEPROP 1 LAST TOLERANCE 5%
J 0
(-5475 1375);
DISPLAY 0.617021 (-5475 1375);
PAINT SKYBLUE (-5475 1375);
FORCEPROP 1 LAST VALUE 0.0
J 2
(-5500 1375);
DISPLAY 0.617021 (-5500 1375);
PAINT SKYBLUE (-5500 1375);
FORCEPROP 1 LAST LOCATION R1E7
J 0
(-5525 1500);
DISPLAY 0.617021 (-5525 1500);
PAINT AQUA (-5525 1500);
FORCEPROP 1 LASTPIN (-5575 1450) $PN 1
J 0
(-5563 1462);
DISPLAY 0.617021 (-5563 1462);
PAINT GREEN (-5563 1462);
FORCEPROP 1 LAST PACK_TYPE 0402
J 0
(-5600 1250);
DISPLAY 0.617021 (-5600 1250);
PAINT SKYBLUE (-5600 1250);
FORCEPROP 2 LAST BOM_COST PROC_VRD_VCCIN_CPU0
J 0
(-5600 1600);
PAINT MONO (-5600 1600);
DISPLAY INVISIBLE (-5600 1600);
FORCEPROP 2 LAST CDS_SEC 1
J 0
(-5525 1650);
PAINT MONO (-5525 1650);
DISPLAY INVISIBLE (-5525 1650);
FORCEPROP 2 LAST $SEC 1
J 0
(-5525 1650);
PAINT MONO (-5525 1650);
DISPLAY INVISIBLE (-5525 1650);
FORCEPROP 1 LAST PATH I10
J 0
(-5525 1600);
DISPLAY 0.978723 (-5525 1600);
PAINT WHITE (-5525 1600);
DISPLAY INVISIBLE (-5525 1600);
FORCEPROP 2 LAST ROOM PVCCIN_CPU1_VSENSE_VR
J 0
(-5525 1550);
PAINT ORANGE (-5525 1550);
DISPLAY INVISIBLE (-5525 1550);
FORCEPROP 2 LAST CDS_LIB mstr_discrete
J 0
(-5475 1450);
PAINT ORANGE (-5475 1450);
DISPLAY INVISIBLE (-5475 1450);
FORCEPROP 2 LAST CDS_LOCATION R1E7
J 0
(-5525 1500);
DISPLAY 0.617021 (-5525 1500);
PAINT AQUA (-5525 1500);
DISPLAY INVISIBLE (-5525 1500);
FORCEADD RES..1
(-5500 1900);
FORCEPROP 1 LAST TOLERANCE 5%
J 0
(-5500 1825);
DISPLAY 0.617021 (-5500 1825);
PAINT SKYBLUE (-5500 1825);
FORCEPROP 1 LASTPIN (-5400 1900) $PN 2
J 0
(-5438 1912);
DISPLAY 0.617021 (-5438 1912);
PAINT GREEN (-5438 1912);
FORCEPROP 1 LAST LOCATION R1E6
J 0
(-5550 1950);
DISPLAY 0.617021 (-5550 1950);
PAINT AQUA (-5550 1950);
FORCEPROP 1 LAST VALUE 0.0
J 2
(-5525 1825);
DISPLAY 0.617021 (-5525 1825);
PAINT SKYBLUE (-5525 1825);
FORCEPROP 1 LASTPIN (-5600 1900) $PN 1
J 0
(-5588 1912);
DISPLAY 0.617021 (-5588 1912);
PAINT GREEN (-5588 1912);
FORCEPROP 1 LAST MATERIAL CHIP
J 0
(-5500 1750);
DISPLAY 0.617021 (-5500 1750);
PAINT SKYBLUE (-5500 1750);
FORCEPROP 1 LAST PACK_TYPE 0402
J 0
(-5625 1700);
DISPLAY 0.617021 (-5625 1700);
PAINT SKYBLUE (-5625 1700);
FORCEPROP 1 LAST WATTAGE 1/16W
J 2
(-5525 1750);
DISPLAY 0.617021 (-5525 1750);
PAINT SKYBLUE (-5525 1750);
FORCEPROP 1 LAST PART_NUMBER G21497-005
J 0
(-5625 2000);
DISPLAY 0.617021 (-5625 2000);
PAINT BLUE (-5625 2000);
FORCEPROP 2 LAST BOM_COST PROC_VRD_VCCIN_CPU0
J 0
(-5625 2050);
PAINT MONO (-5625 2050);
DISPLAY INVISIBLE (-5625 2050);
FORCEPROP 2 LAST CDS_SEC 1
J 0
(-5550 2100);
PAINT MONO (-5550 2100);
DISPLAY INVISIBLE (-5550 2100);
FORCEPROP 2 LAST $SEC 1
J 0
(-5550 2100);
PAINT MONO (-5550 2100);
DISPLAY INVISIBLE (-5550 2100);
FORCEPROP 1 LAST PATH I11
J 0
(-5550 2050);
DISPLAY 0.978723 (-5550 2050);
PAINT WHITE (-5550 2050);
DISPLAY INVISIBLE (-5550 2050);
FORCEPROP 2 LAST CDS_LIB mstr_discrete
J 0
(-5500 1900);
PAINT ORANGE (-5500 1900);
DISPLAY INVISIBLE (-5500 1900);
FORCEPROP 2 LAST ROOM PVCCIN_CPU1_VSENSE_VR
J 0
(-5550 2000);
PAINT ORANGE (-5550 2000);
DISPLAY INVISIBLE (-5550 2000);
FORCEPROP 2 LAST CDS_LOCATION R1E6
J 0
(-5550 1950);
DISPLAY 0.617021 (-5550 1950);
PAINT AQUA (-5550 1950);
DISPLAY INVISIBLE (-5550 1950);
FORCEADD GND..1
(-4825 775);
FORCEPROP 3 LASTPIN (-4825 825) SIG_NAME GND\g
J 0
(-4815 835);
DISPLAY 0.659574 (-4815 835);
PAINT MONO (-4815 835);
DISPLAY INVISIBLE (-4815 835);
FORCEPROP 1 LAST VOLTAGE 0
J 0
(-4825 775);
PAINT SKYBLUE (-4825 775);
DISPLAY INVISIBLE (-4825 775);
FORCEPROP 2 LAST CDS_LIB mstr_symbols
J 0
(-4825 775);
PAINT ORANGE (-4825 775);
DISPLAY INVISIBLE (-4825 775);
FORCEPROP 1 LAST SIZE 1B
J 0
(-4750 725);
DISPLAY 0.893617 (-4750 725);
PAINT GREEN (-4750 725);
DISPLAY INVISIBLE (-4750 725);
FORCEPROP 1 LAST PATH I12
J 0
(-4750 775);
DISPLAY 0.872340 (-4750 775);
PAINT AQUA (-4750 775);
DISPLAY INVISIBLE (-4750 775);
FORCEPROP 2 LAST BOM_COST PROC_VRD_VCCIN_CPU0
J 0
(-5200 850);
PAINT MONO (-5200 850);
DISPLAY INVISIBLE (-5200 850);
FORCEPROP 2 LAST ROOM PVCCIN_CPU1_VSENSE_VR
J 0
(-5375 850);
PAINT ORANGE (-5375 850);
DISPLAY INVISIBLE (-5375 850);
FORCEPROP 1 LAST BODY_TYPE PLUMBING
J 0
(-4870 732);
DISPLAY 0.340426 (-4870 732);
PAINT GREEN (-4870 732);
DISPLAY INVISIBLE (-4870 732);
FORCEPROP 1 LAST HDL_POWER GND
J 0
(-4825 925);
DISPLAY 0.893617 (-4825 925);
PAINT GREEN (-4825 925);
DISPLAY INVISIBLE (-4825 925);
FORCEADD OFFPAGE..2
(-4300 1450);
FORCEPROP 2 LAST $XR0 71 
J 0
(-4111 1450);
DISPLAY 0.638298 (-4111 1450);
PAINT MONO (-4111 1450);
FORCEPROP 2 LAST BOM_COST PROC_VRD_VCCIN_CPU0
J 0
(-4100 1500);
PAINT MONO (-4100 1500);
DISPLAY INVISIBLE (-4100 1500);
FORCEPROP 2 LAST PATH I13
J 0
(-4110 1485);
DISPLAY 1.021277 (-4110 1485);
PAINT ORANGE (-4110 1485);
DISPLAY INVISIBLE (-4110 1485);
FORCEPROP 2 LAST CDS_LIB mstr_standard
J 0
(-4300 1450);
PAINT ORANGE (-4300 1450);
DISPLAY INVISIBLE (-4300 1450);
FORCEPROP 2 LAST ROOM PVCCIN_CPU1_VSENSE_VR
J 0
(-4700 1525);
PAINT ORANGE (-4700 1525);
DISPLAY INVISIBLE (-4700 1525);
FORCEPROP 1 LAST OFFPAGE TRUE
J 0
(-3975 1325);
DISPLAY 0.893617 (-3975 1325);
PAINT GREEN (-3975 1325);
DISPLAY INVISIBLE (-3975 1325);
FORCEPROP 1 LAST COMMENT_BODY TRUE
J 0
(-4345 1355);
DISPLAY 0.893617 (-4345 1355);
PAINT GREEN (-4345 1355);
DISPLAY INVISIBLE (-4345 1355);
FORCEADD OFFPAGE..2
(-4300 1900);
FORCEPROP 2 LAST $XR0 71 
J 0
(-4111 1900);
DISPLAY 0.638298 (-4111 1900);
PAINT MONO (-4111 1900);
FORCEPROP 2 LAST BOM_COST PROC_VRD_VCCIN_CPU0
J 0
(-3975 1950);
PAINT MONO (-3975 1950);
DISPLAY INVISIBLE (-3975 1950);
FORCEPROP 2 LAST PATH I14
J 0
(-4110 1935);
DISPLAY 1.021277 (-4110 1935);
PAINT ORANGE (-4110 1935);
DISPLAY INVISIBLE (-4110 1935);
FORCEPROP 2 LAST CDS_LIB mstr_standard
J 2
(-4300 1900);
PAINT ORANGE (-4300 1900);
DISPLAY INVISIBLE (-4300 1900);
FORCEPROP 2 LAST ROOM PVCCIN_CPU1_VSENSE_VR
J 0
(-4700 1975);
PAINT ORANGE (-4700 1975);
DISPLAY INVISIBLE (-4700 1975);
FORCEPROP 1 LAST OFFPAGE TRUE
J 0
(-3975 1775);
DISPLAY 0.893617 (-3975 1775);
PAINT GREEN (-3975 1775);
DISPLAY INVISIBLE (-3975 1775);
FORCEPROP 1 LAST COMMENT_BODY TRUE
J 0
(-4345 1805);
DISPLAY 0.893617 (-4345 1805);
PAINT GREEN (-4345 1805);
DISPLAY INVISIBLE (-4345 1805);
FORCEADD RES..1
(-5500 2300);
FORCEPROP 1 LAST PART_NUMBER G21796-017
J 0
(-5550 2400);
DISPLAY 0.617021 (-5550 2400);
PAINT BLUE (-5550 2400);
FORCEPROP 1 LAST LOCATION R1E4
J 0
(-5550 2350);
DISPLAY 0.617021 (-5550 2350);
PAINT AQUA (-5550 2350);
FORCEPROP 1 LAST TOLERANCE 1%
J 0
(-5450 2225);
DISPLAY 0.617021 (-5450 2225);
PAINT SKYBLUE (-5450 2225);
FORCEPROP 1 LASTPIN (-5400 2300) $PN 2
J 0
(-5438 2312);
DISPLAY 0.617021 (-5438 2312);
PAINT GREEN (-5438 2312);
FORCEPROP 1 LASTPIN (-5600 2300) $PN 1
J 0
(-5588 2312);
DISPLAY 0.617021 (-5588 2312);
PAINT GREEN (-5588 2312);
FORCEPROP 1 LAST PACK_TYPE 0402
J 0
(-5575 2125);
DISPLAY 0.617021 (-5575 2125);
PAINT SKYBLUE (-5575 2125);
FORCEPROP 1 LAST WATTAGE 1/16W
J 2
(-5500 2175);
DISPLAY 0.617021 (-5500 2175);
PAINT SKYBLUE (-5500 2175);
FORCEPROP 1 LAST VALUE 100.0
J 2
(-5500 2225);
DISPLAY 0.617021 (-5500 2225);
PAINT SKYBLUE (-5500 2225);
FORCEPROP 2 LAST ROOM PVCCIN_CPU1_VSENSE_VR
J 0
(-5550 2400);
PAINT ORANGE (-5550 2400);
DISPLAY INVISIBLE (-5550 2400);
FORCEPROP 2 LAST $SEC 1
J 0
(-5550 2500);
PAINT MONO (-5550 2500);
DISPLAY INVISIBLE (-5550 2500);
FORCEPROP 2 LAST CDS_LOCATION R1E4
J 0
(-5550 2350);
DISPLAY 0.617021 (-5550 2350);
PAINT AQUA (-5550 2350);
DISPLAY INVISIBLE (-5550 2350);
FORCEPROP 1 LAST PATH I15
J 0
(-5550 2450);
DISPLAY 0.978723 (-5550 2450);
PAINT WHITE (-5550 2450);
DISPLAY INVISIBLE (-5550 2450);
FORCEPROP 2 LAST CDS_SEC 1
J 0
(-5550 2500);
PAINT MONO (-5550 2500);
DISPLAY INVISIBLE (-5550 2500);
FORCEPROP 2 LAST BOM_COST PROC_VRD_VCCIN_CPU0
J 0
(-5550 2450);
PAINT MONO (-5550 2450);
DISPLAY INVISIBLE (-5550 2450);
FORCEPROP 2 LAST CDS_LIB mstr_discrete
J 0
(-5500 2300);
PAINT ORANGE (-5500 2300);
DISPLAY INVISIBLE (-5500 2300);
FORCEPROP 1 LAST MATERIAL CHIP
J 0
(-5475 2175);
PAINT SKYBLUE (-5475 2175);
DISPLAY INVISIBLE (-5475 2175);
FORCEADD CAP..1
(-6225 4025);
FORCEPROP 1 LAST LOCATION C1C26
J 0
(-6175 4125);
DISPLAY 0.617021 (-6175 4125);
PAINT AQUA (-6175 4125);
FORCEPROP 1 LASTPIN (-6225 4125) $PN 1
J 0
(-6215 4105);
DISPLAY 0.617021 (-6215 4105);
PAINT ORANGE (-6215 4105);
FORCEPROP 1 LAST VALUE 1.0UF
J 0
(-6175 4075);
DISPLAY 0.617021 (-6175 4075);
PAINT SKYBLUE (-6175 4075);
FORCEPROP 1 LAST PART_NUMBER D97712-011
J 0
(-6175 3875);
DISPLAY 0.617021 (-6175 3875);
PAINT BLUE (-6175 3875);
FORCEPROP 1 LAST TOLERANCE 10%
J 0
(-6175 3975);
DISPLAY 0.617021 (-6175 3975);
PAINT SKYBLUE (-6175 3975);
FORCEPROP 1 LAST MATERIAL X6S
J 0
(-6175 3925);
DISPLAY 0.617021 (-6175 3925);
PAINT SKYBLUE (-6175 3925);
FORCEPROP 1 LASTPIN (-6225 3925) $PN 2
J 0
(-6215 3905);
DISPLAY 0.617021 (-6215 3905);
PAINT ORANGE (-6215 3905);
FORCEPROP 1 LAST PACK_TYPE 0402
J 0
(-6175 3825);
DISPLAY 0.617021 (-6175 3825);
PAINT SKYBLUE (-6175 3825);
FORCEPROP 1 LAST VOLTAGE 16V
J 0
(-6175 4025);
DISPLAY 0.617021 (-6175 4025);
PAINT SKYBLUE (-6175 4025);
FORCEPROP 2 LAST SEC_TYPE 0402
J 0
(-6175 4225);
DISPLAY 1.021277 (-6175 4225);
PAINT ORANGE (-6175 4225);
DISPLAY INVISIBLE (-6175 4225);
FORCEPROP 2 LAST SEC 1
J 0
(-6175 4225);
DISPLAY 0.680851 (-6175 4225);
PAINT MONO (-6175 4225);
DISPLAY INVISIBLE (-6175 4225);
FORCEPROP 1 LAST PATH I16
J 0
(-6175 4175);
DISPLAY 0.978723 (-6175 4175);
PAINT WHITE (-6175 4175);
DISPLAY INVISIBLE (-6175 4175);
FORCEPROP 2 LAST ROOM PVCCIN_CPU1_PWR_VR
J 0
(-6175 4175);
DISPLAY 1.361702 (-6175 4175);
PAINT ORANGE (-6175 4175);
DISPLAY INVISIBLE (-6175 4175);
FORCEPROP 2 LAST CDS_LIB mstr_discrete
J 0
(-6225 4025);
PAINT ORANGE (-6225 4025);
DISPLAY INVISIBLE (-6225 4025);
FORCEADD CAP_A..1
(-5925 4025);
FORCEPROP 1 LAST VALUE 0.1UF
J 0
(-5875 4075);
DISPLAY 0.617021 (-5875 4075);
PAINT SKYBLUE (-5875 4075);
FORCEPROP 1 LAST LOCATION C1C25
J 0
(-5875 4125);
DISPLAY 0.617021 (-5875 4125);
PAINT AQUA (-5875 4125);
FORCEPROP 1 LAST VOLTAGE 16V
J 0
(-5875 4025);
DISPLAY 0.617021 (-5875 4025);
PAINT SKYBLUE (-5875 4025);
FORCEPROP 1 LAST PART_NUMBER A36096-030
J 0
(-5875 3875);
DISPLAY 0.617021 (-5875 3875);
PAINT BLUE (-5875 3875);
FORCEPROP 1 LASTPIN (-5925 3925) $PN 2
J 0
(-5915 3905);
DISPLAY 0.617021 (-5915 3905);
PAINT ORANGE (-5915 3905);
FORCEPROP 1 LAST MATERIAL X7R
J 0
(-5875 3925);
DISPLAY 0.617021 (-5875 3925);
PAINT SKYBLUE (-5875 3925);
FORCEPROP 1 LAST TOLERANCE 10%
J 0
(-5875 3975);
DISPLAY 0.617021 (-5875 3975);
PAINT SKYBLUE (-5875 3975);
FORCEPROP 1 LASTPIN (-5925 4125) $PN 1
J 0
(-5915 4105);
DISPLAY 0.617021 (-5915 4105);
PAINT ORANGE (-5915 4105);
FORCEPROP 1 LAST PACK_TYPE 0402V
J 0
(-5875 3825);
DISPLAY 0.617021 (-5875 3825);
PAINT SKYBLUE (-5875 3825);
FORCEPROP 2 LAST CDS_LIB dev_discrete
J 0
(-5925 4025);
PAINT ORANGE (-5925 4025);
DISPLAY INVISIBLE (-5925 4025);
FORCEPROP 2 LAST SEC 1
J 0
(-5875 4225);
DISPLAY 0.680851 (-5875 4225);
PAINT MONO (-5875 4225);
DISPLAY INVISIBLE (-5875 4225);
FORCEPROP 2 LAST SEC_TYPE 0402V
J 0
(-5875 4225);
DISPLAY 1.021277 (-5875 4225);
PAINT ORANGE (-5875 4225);
DISPLAY INVISIBLE (-5875 4225);
FORCEPROP 2 LAST CDS_SEC 1
J 0
(-5875 4175);
PAINT ORANGE (-5875 4175);
DISPLAY INVISIBLE (-5875 4175);
FORCEPROP 2 LAST ROOM PVCCIN_CPU1_PWR_VR
J 0
(-5875 4175);
DISPLAY 1.361702 (-5875 4175);
PAINT ORANGE (-5875 4175);
DISPLAY INVISIBLE (-5875 4175);
FORCEPROP 1 LAST PATH I17
J 0
(-5875 4175);
DISPLAY 0.978723 (-5875 4175);
PAINT WHITE (-5875 4175);
DISPLAY INVISIBLE (-5875 4175);
FORCEADD CAP..1
(-5625 4025);
FORCEPROP 1 LAST VALUE 1.0UF
J 0
(-5575 4075);
DISPLAY 0.617021 (-5575 4075);
PAINT SKYBLUE (-5575 4075);
FORCEPROP 1 LAST LOCATION C1D32
J 0
(-5575 4125);
DISPLAY 0.617021 (-5575 4125);
PAINT AQUA (-5575 4125);
FORCEPROP 1 LAST PART_NUMBER D97712-011
J 0
(-5575 3875);
DISPLAY 0.617021 (-5575 3875);
PAINT BLUE (-5575 3875);
FORCEPROP 1 LASTPIN (-5625 4125) $PN 1
J 0
(-5615 4105);
DISPLAY 0.617021 (-5615 4105);
PAINT ORANGE (-5615 4105);
FORCEPROP 1 LASTPIN (-5625 3925) $PN 2
J 0
(-5615 3905);
DISPLAY 0.617021 (-5615 3905);
PAINT ORANGE (-5615 3905);
FORCEPROP 1 LAST VOLTAGE 16V
J 0
(-5575 4025);
DISPLAY 0.617021 (-5575 4025);
PAINT SKYBLUE (-5575 4025);
FORCEPROP 1 LAST TOLERANCE 10%
J 0
(-5575 3975);
DISPLAY 0.617021 (-5575 3975);
PAINT SKYBLUE (-5575 3975);
FORCEPROP 1 LAST PACK_TYPE 0402
J 0
(-5575 3825);
DISPLAY 0.617021 (-5575 3825);
PAINT SKYBLUE (-5575 3825);
FORCEPROP 1 LAST MATERIAL X6S
J 0
(-5575 3925);
DISPLAY 0.617021 (-5575 3925);
PAINT SKYBLUE (-5575 3925);
FORCEPROP 2 LAST SEC_TYPE 0402
J 0
(-5575 4225);
DISPLAY 1.021277 (-5575 4225);
PAINT ORANGE (-5575 4225);
DISPLAY INVISIBLE (-5575 4225);
FORCEPROP 2 LAST SEC 1
J 0
(-5575 4225);
DISPLAY 0.680851 (-5575 4225);
PAINT MONO (-5575 4225);
DISPLAY INVISIBLE (-5575 4225);
FORCEPROP 2 LAST ROOM PVCCIN_CPU1_PWR_VR
J 0
(-5575 4175);
DISPLAY 1.361702 (-5575 4175);
PAINT ORANGE (-5575 4175);
DISPLAY INVISIBLE (-5575 4175);
FORCEPROP 1 LAST PATH I18
J 0
(-5575 4175);
DISPLAY 0.978723 (-5575 4175);
PAINT WHITE (-5575 4175);
DISPLAY INVISIBLE (-5575 4175);
FORCEPROP 2 LAST CDS_LIB mstr_discrete
J 0
(-5625 4025);
PAINT ORANGE (-5625 4025);
DISPLAY INVISIBLE (-5625 4025);
FORCEADD PVCCIN_CPU1..1
(-4650 2450);
FORCEPROP 3 LASTPIN (-4650 2400) SIG_NAME PVCCIN_CPU1\g
J 0
(-4640 2410);
DISPLAY 0.659574 (-4640 2410);
PAINT MONO (-4640 2410);
DISPLAY INVISIBLE (-4640 2410);
FORCEPROP 1 LAST VOLTAGE 2.0V
J 0
(-4695 2407);
DISPLAY 0.340426 (-4695 2407);
PAINT SKYBLUE (-4695 2407);
DISPLAY INVISIBLE (-4695 2407);
FORCEPROP 2 LAST CDS_LIB mstr_symbols
J 0
(-4650 2450);
PAINT ORANGE (-4650 2450);
DISPLAY INVISIBLE (-4650 2450);
FORCEPROP 1 LAST PATH I19
J 0
(-4600 2475);
DISPLAY 0.872340 (-4600 2475);
PAINT AQUA (-4600 2475);
DISPLAY INVISIBLE (-4600 2475);
FORCEPROP 1 LAST BODY_TYPE PLUMBING
J 0
(-4695 2407);
DISPLAY 0.340426 (-4695 2407);
PAINT GREEN (-4695 2407);
DISPLAY INVISIBLE (-4695 2407);
FORCEPROP 1 LAST HDL_POWER PVCCIN_CPU1
J 1
(-4650 2500);
DISPLAY 0.872340 (-4650 2500);
PAINT GREEN (-4650 2500);
DISPLAY INVISIBLE (-4650 2500);
FORCEADD OFFPAGE..1
(-7625 1850);
FORCEPROP 2 LAST $XR0 206 
J 0
(-7877 1850);
DISPLAY 0.638298 (-7877 1850);
PAINT MONO (-7877 1850);
FORCEPROP 2 LAST CDS_LIB mstr_standard
J 2
(-7625 1850);
PAINT ORANGE (-7625 1850);
DISPLAY INVISIBLE (-7625 1850);
FORCEPROP 2 LAST PATH I2
J 0
(-7860 1885);
DISPLAY 1.021277 (-7860 1885);
PAINT ORANGE (-7860 1885);
DISPLAY INVISIBLE (-7860 1885);
FORCEPROP 2 LAST BOM_COST PROC_VRD_VCCIN_CPU0
J 0
(-7825 1900);
PAINT MONO (-7825 1900);
DISPLAY INVISIBLE (-7825 1900);
FORCEPROP 2 LAST ROOM PVCCIN_CPU1_VSENSE_VR
J 0
(-8150 1925);
PAINT ORANGE (-8150 1925);
DISPLAY INVISIBLE (-8150 1925);
FORCEPROP 1 LAST OFFPAGE TRUE
J 0
(-7300 1725);
DISPLAY 0.893617 (-7300 1725);
PAINT GREEN (-7300 1725);
DISPLAY INVISIBLE (-7300 1725);
FORCEPROP 1 LAST COMMENT_BODY TRUE
J 0
(-7500 1750);
DISPLAY 0.893617 (-7500 1750);
PAINT GREEN (-7500 1750);
DISPLAY INVISIBLE (-7500 1750);
FORCEADD CAP..1
R 2
(-5900 3450);
FORCEPROP 1 LAST PACK_TYPE 0402
J 2
(-5950 3250);
DISPLAY 0.617021 (-5950 3250);
PAINT SKYBLUE (-5950 3250);
FORCEPROP 1 LAST LOCATION C1C24
J 2
(-5950 3550);
DISPLAY 0.617021 (-5950 3550);
PAINT AQUA (-5950 3550);
FORCEPROP 1 LASTPIN (-5900 3550) $PN 1
J 2
(-5910 3530);
DISPLAY 0.617021 (-5910 3530);
PAINT ORANGE (-5910 3530);
FORCEPROP 1 LAST VOLTAGE 16V
J 2
(-5950 3450);
DISPLAY 0.617021 (-5950 3450);
PAINT SKYBLUE (-5950 3450);
FORCEPROP 1 LAST TOLERANCE 10%
J 2
(-5950 3400);
DISPLAY 0.617021 (-5950 3400);
PAINT SKYBLUE (-5950 3400);
FORCEPROP 1 LAST MATERIAL X7R
J 2
(-5950 3350);
DISPLAY 0.617021 (-5950 3350);
PAINT SKYBLUE (-5950 3350);
FORCEPROP 1 LAST PART_NUMBER A36096-104
J 2
(-5950 3300);
DISPLAY 0.617021 (-5950 3300);
PAINT BLUE (-5950 3300);
FORCEPROP 1 LASTPIN (-5900 3350) $PN 2
J 2
(-5910 3330);
DISPLAY 0.617021 (-5910 3330);
PAINT ORANGE (-5910 3330);
FORCEPROP 1 LAST VALUE 0.220UF
J 2
(-5950 3500);
DISPLAY 0.617021 (-5950 3500);
PAINT SKYBLUE (-5950 3500);
FORCEPROP 2 LAST CDS_LOCATION C1C24
J 2
(-5950 3550);
DISPLAY 0.617021 (-5950 3550);
PAINT AQUA (-5950 3550);
DISPLAY INVISIBLE (-5950 3550);
FORCEPROP 2 LAST CDS_LIB mstr_discrete
J 0
(-5900 3450);
PAINT ORANGE (-5900 3450);
DISPLAY INVISIBLE (-5900 3450);
FORCEPROP 2 LAST ROOM PVCCIN_CPU1_PWR_VR
J 0
(-5975 3600);
DISPLAY 1.361702 (-5975 3600);
PAINT ORANGE (-5975 3600);
DISPLAY INVISIBLE (-5975 3600);
FORCEPROP 1 LAST PATH I20
J 2
(-5950 3600);
DISPLAY 0.978723 (-5950 3600);
PAINT WHITE (-5950 3600);
DISPLAY INVISIBLE (-5950 3600);
FORCEPROP 2 LAST NO_XNET_CONNECTION 1
J 0
(-5950 3650);
PAINT MONO (-5950 3650);
DISPLAY INVISIBLE (-5950 3650);
FORCEPROP 2 LAST SEC 1
J 0
(-5950 3650);
PAINT MONO (-5950 3650);
DISPLAY INVISIBLE (-5950 3650);
FORCEPROP 0 LAST SPOF TRUE
J 0
(-5950 3650);
DISPLAY 1.021277 (-5950 3650);
PAINT ORANGE (-5950 3650);
DISPLAY INVISIBLE (-5950 3650);
FORCEPROP 2 LAST SEC_TYPE 0402
J 0
(-5950 3650);
DISPLAY 1.021277 (-5950 3650);
PAINT ORANGE (-5950 3650);
DISPLAY INVISIBLE (-5950 3650);
FORCEADD CAP..1
(-4800 4025);
FORCEPROP 1 LAST LOCATION C1D33
J 0
(-4750 4125);
DISPLAY 0.617021 (-4750 4125);
PAINT AQUA (-4750 4125);
FORCEPROP 1 LAST VALUE 0.22UF
J 0
(-4750 4075);
DISPLAY 0.617021 (-4750 4075);
PAINT SKYBLUE (-4750 4075);
FORCEPROP 1 LAST VOLTAGE 16V
J 0
(-4750 4025);
DISPLAY 0.617021 (-4750 4025);
PAINT SKYBLUE (-4750 4025);
FORCEPROP 1 LAST TOLERANCE 10%
J 0
(-4750 3975);
DISPLAY 0.617021 (-4750 3975);
PAINT SKYBLUE (-4750 3975);
FORCEPROP 1 LASTPIN (-4800 4125) $PN 1
J 0
(-4790 4105);
DISPLAY 0.617021 (-4790 4105);
PAINT ORANGE (-4790 4105);
FORCEPROP 1 LAST PART_NUMBER A36096-155
J 0
(-4750 3875);
DISPLAY 0.617021 (-4750 3875);
PAINT BLUE (-4750 3875);
FORCEPROP 1 LAST PACK_TYPE 0402
J 0
(-4750 3825);
DISPLAY 0.617021 (-4750 3825);
PAINT SKYBLUE (-4750 3825);
FORCEPROP 1 LASTPIN (-4800 3925) $PN 2
J 0
(-4790 3905);
DISPLAY 0.617021 (-4790 3905);
PAINT ORANGE (-4790 3905);
FORCEPROP 1 LAST MATERIAL X7R
J 0
(-4750 3925);
DISPLAY 0.617021 (-4750 3925);
PAINT SKYBLUE (-4750 3925);
FORCEPROP 2 LAST CDS_LIB mstr_discrete
J 0
(-4800 4025);
PAINT ORANGE (-4800 4025);
DISPLAY INVISIBLE (-4800 4025);
FORCEPROP 2 LAST ROOM PVCCIN_CPU1_PWR_VR
J 0
(-4750 4175);
DISPLAY 1.361702 (-4750 4175);
PAINT ORANGE (-4750 4175);
DISPLAY INVISIBLE (-4750 4175);
FORCEPROP 1 LAST PATH I22
J 0
(-4750 4175);
DISPLAY 0.978723 (-4750 4175);
PAINT WHITE (-4750 4175);
DISPLAY INVISIBLE (-4750 4175);
FORCEPROP 2 LAST SEC 1
J 0
(-4750 4225);
DISPLAY 0.680851 (-4750 4225);
PAINT MONO (-4750 4225);
DISPLAY INVISIBLE (-4750 4225);
FORCEPROP 2 LAST SEC_TYPE 0402
J 0
(-4750 4225);
DISPLAY 1.021277 (-4750 4225);
PAINT ORANGE (-4750 4225);
DISPLAY INVISIBLE (-4750 4225);
FORCEADD VCC_CORE..1
(-6350 4450);
FORCEPROP 3 LASTPIN (-6350 4400) SIG_NAME VR_FET_SW_P12V_STBY_PVCCIN_CPU1\g
J 0
(-6340 4410);
DISPLAY 0.659574 (-6340 4410);
PAINT MONO (-6340 4410);
DISPLAY INVISIBLE (-6340 4410);
FORCEPROP 1 LAST HDL_POWER VR_FET_SW_P12V_STBY_PVCCIN_CPU1
J 1
(-6300 4500);
DISPLAY 0.617021 (-6300 4500);
PAINT GREEN (-6300 4500);
FORCEPROP 1 LAST PATH I23
J 0
(-6300 4475);
DISPLAY 0.872340 (-6300 4475);
PAINT AQUA (-6300 4475);
DISPLAY INVISIBLE (-6300 4475);
FORCEPROP 2 LAST CDS_LIB mstr_symbols
J 0
(-6350 4450);
DISPLAY 1.936170 (-6350 4450);
PAINT ORANGE (-6350 4450);
DISPLAY INVISIBLE (-6350 4450);
FORCEADD RES..2
(-6300 1700);
FORCEPROP 1 LAST PART_NUMBER G21796-026
J 0
(-6260 1575);
DISPLAY 0.617021 (-6260 1575);
PAINT BLUE (-6260 1575);
FORCEPROP 1 LAST MATERIAL EMPTY
J 0
(-6260 1625);
DISPLAY 0.617021 (-6260 1625);
PAINT RED (-6260 1625);
FORCEPROP 1 LAST LOCATION R1E5
J 0
(-6255 1825);
DISPLAY 0.617021 (-6255 1825);
PAINT AQUA (-6255 1825);
FORCEPROP 1 LAST VALUE 1.00K
J 0
(-6255 1775);
DISPLAY 0.617021 (-6255 1775);
PAINT SKYBLUE (-6255 1775);
FORCEPROP 1 LAST PACK_TYPE 0402
J 0
(-6260 1525);
DISPLAY 0.617021 (-6260 1525);
PAINT SKYBLUE (-6260 1525);
FORCEPROP 1 LAST WATTAGE 1/16W
J 0
(-6260 1675);
DISPLAY 0.617021 (-6260 1675);
PAINT SKYBLUE (-6260 1675);
FORCEPROP 1 LAST TOLERANCE 1%
J 0
(-6255 1725);
DISPLAY 0.617021 (-6255 1725);
PAINT SKYBLUE (-6255 1725);
FORCEPROP 1 LASTPIN (-6300 1600) $PN 2
J 0
(-6295 1610);
DISPLAY 0.617021 (-6295 1610);
PAINT GREEN (-6295 1610);
FORCEPROP 1 LASTPIN (-6300 1800) $PN 1
J 0
(-6295 1762);
DISPLAY 0.617021 (-6295 1762);
PAINT GREEN (-6295 1762);
FORCEPROP 2 LAST BOM_COST PROC_VRD_VCCIN_CPU0
J 0
(-6250 1875);
PAINT MONO (-6250 1875);
DISPLAY INVISIBLE (-6250 1875);
FORCEPROP 2 LAST CDS_SEC 1
J 0
(-6250 1925);
PAINT MONO (-6250 1925);
DISPLAY INVISIBLE (-6250 1925);
FORCEPROP 2 LAST $SEC 1
J 0
(-6250 1925);
PAINT MONO (-6250 1925);
DISPLAY INVISIBLE (-6250 1925);
FORCEPROP 2 LAST CDS_LOCATION R1E5
J 0
(-6255 1825);
DISPLAY 0.617021 (-6255 1825);
PAINT AQUA (-6255 1825);
DISPLAY INVISIBLE (-6255 1825);
FORCEPROP 1 LAST PATH I3
J 0
(-6250 1875);
DISPLAY 0.978723 (-6250 1875);
PAINT WHITE (-6250 1875);
DISPLAY INVISIBLE (-6250 1875);
FORCEPROP 2 LAST ROOM PVCCIN_CPU1_VSENSE_VR
J 0
(-6250 1875);
PAINT MONO (-6250 1875);
DISPLAY INVISIBLE (-6250 1875);
FORCEPROP 2 LAST CDS_LIB mstr_discrete
J 0
(-6300 1700);
PAINT ORANGE (-6300 1700);
DISPLAY INVISIBLE (-6300 1700);
FORCEADD GND..1
(-2675 3125);
FORCEPROP 3 LASTPIN (-2675 3175) SIG_NAME GND\g
J 0
(-2665 3185);
DISPLAY 0.659574 (-2665 3185);
PAINT MONO (-2665 3185);
DISPLAY INVISIBLE (-2665 3185);
FORCEPROP 2 LAST CDS_LIB mstr_symbols
J 0
(-2675 3125);
DISPLAY 1.936170 (-2675 3125);
PAINT ORANGE (-2675 3125);
DISPLAY INVISIBLE (-2675 3125);
FORCEPROP 1 LAST PATH I34
J 0
(-2600 3125);
DISPLAY 0.872340 (-2600 3125);
PAINT AQUA (-2600 3125);
DISPLAY INVISIBLE (-2600 3125);
FORCEPROP 1 LAST SIZE 1B
J 0
(-2600 3075);
DISPLAY 1.723404 (-2600 3075);
PAINT GREEN (-2600 3075);
DISPLAY INVISIBLE (-2600 3075);
FORCEPROP 1 LAST VOLTAGE 0
J 0
(-2675 3125);
PAINT SKYBLUE (-2675 3125);
DISPLAY INVISIBLE (-2675 3125);
FORCEPROP 2 LAST BOM_COST PROC_VRD_VCCIN_CPU0
J 0
(-3050 3200);
DISPLAY 1.446809 (-3050 3200);
PAINT MONO (-3050 3200);
DISPLAY INVISIBLE (-3050 3200);
FORCEPROP 2 LAST ROOM PVCCIN_CPU1_PWR_VR
J 0
(-3225 3200);
DISPLAY 1.936170 (-3225 3200);
PAINT ORANGE (-3225 3200);
DISPLAY INVISIBLE (-3225 3200);
FORCEPROP 1 LAST BODY_TYPE PLUMBING
J 0
(-2720 3082);
DISPLAY 0.340426 (-2720 3082);
PAINT GREEN (-2720 3082);
DISPLAY INVISIBLE (-2720 3082);
FORCEPROP 1 LAST HDL_POWER GND
J 0
(-2675 3275);
DISPLAY 1.723404 (-2675 3275);
PAINT GREEN (-2675 3275);
DISPLAY INVISIBLE (-2675 3275);
FORCEADD CAPP..1
(-1425 2075);
FORCEPROP 1 LAST VALUE 270UF
J 0
(-1375 2125);
DISPLAY 0.617021 (-1375 2125);
PAINT SKYBLUE (-1375 2125);
FORCEPROP 1 LAST LOCATION C1C1
J 0
(-1375 2175);
DISPLAY 0.617021 (-1375 2175);
PAINT AQUA (-1375 2175);
FORCEPROP 1 LASTPIN (-1425 2175) $PN 1
J 0
(-1415 2160);
DISPLAY 0.617021 (-1415 2160);
PAINT ORANGE (-1415 2160);
FORCEPROP 1 LAST TOLERANCE 20%
J 0
(-1375 2075);
DISPLAY 0.617021 (-1375 2075);
PAINT SKYBLUE (-1375 2075);
FORCEPROP 1 LAST VOLTAGE 16V
J 0
(-1375 2025);
DISPLAY 0.617021 (-1375 2025);
PAINT SKYBLUE (-1375 2025);
FORCEPROP 1 LAST PACK_TYPE 2626
J 0
(-1375 1925);
DISPLAY 0.617021 (-1375 1925);
PAINT SKYBLUE (-1375 1925);
FORCEPROP 1 LAST MATERIAL OSCON
J 0
(-1375 1975);
DISPLAY 0.617021 (-1375 1975);
PAINT SKYBLUE (-1375 1975);
FORCEPROP 1 LASTPIN (-1425 1975) $PN 2
J 0
(-1415 1960);
DISPLAY 0.617021 (-1415 1960);
PAINT ORANGE (-1415 1960);
FORCEPROP 1 LAST PART_NUMBER A31228-047
J 0
(-1375 1875);
DISPLAY 0.617021 (-1375 1875);
PAINT BLUE (-1375 1875);
FORCEPROP 2 LAST SEC_TYPE 2626
J 0
(-1375 2275);
DISPLAY 1.021277 (-1375 2275);
PAINT ORANGE (-1375 2275);
DISPLAY INVISIBLE (-1375 2275);
FORCEPROP 2 LAST SEC 1
J 0
(-1375 2275);
DISPLAY 0.680851 (-1375 2275);
PAINT MONO (-1375 2275);
DISPLAY INVISIBLE (-1375 2275);
FORCEPROP 2 LAST CDS_LOCATION C1C1
J 0
(-1375 2175);
DISPLAY 0.617021 (-1375 2175);
PAINT AQUA (-1375 2175);
DISPLAY INVISIBLE (-1375 2175);
FORCEPROP 1 LAST PATH I35
J 0
(-1375 2225);
DISPLAY 0.978723 (-1375 2225);
PAINT ORANGE (-1375 2225);
DISPLAY INVISIBLE (-1375 2225);
FORCEPROP 2 LAST ROOM PVCCIN_CPU1_FILTER_VR
J 0
(-1375 2225);
DISPLAY 1.361702 (-1375 2225);
PAINT ORANGE (-1375 2225);
DISPLAY INVISIBLE (-1375 2225);
FORCEPROP 2 LAST CDS_LIB mstr_discrete
J 0
(-1425 2075);
PAINT ORANGE (-1425 2075);
DISPLAY INVISIBLE (-1425 2075);
FORCEADD GND..1
(-1200 1650);
FORCEPROP 3 LASTPIN (-1200 1700) SIG_NAME GND\g
J 0
(-1190 1710);
DISPLAY 0.659574 (-1190 1710);
PAINT MONO (-1190 1710);
DISPLAY INVISIBLE (-1190 1710);
FORCEPROP 1 LAST PATH I36
J 0
(-1125 1650);
DISPLAY 0.872340 (-1125 1650);
PAINT AQUA (-1125 1650);
DISPLAY INVISIBLE (-1125 1650);
FORCEPROP 1 LAST SIZE 1B
J 0
(-1125 1600);
DISPLAY 0.893617 (-1125 1600);
PAINT GREEN (-1125 1600);
DISPLAY INVISIBLE (-1125 1600);
FORCEPROP 1 LAST VOLTAGE 0
J 0
(-1200 1650);
PAINT SKYBLUE (-1200 1650);
DISPLAY INVISIBLE (-1200 1650);
FORCEPROP 2 LAST CDS_LIB mstr_symbols
J 0
(-1200 1650);
PAINT ORANGE (-1200 1650);
DISPLAY INVISIBLE (-1200 1650);
FORCEPROP 2 LAST ROOM PVCCIN_CPU1_FILTER_VR
J 0
(-1750 1725);
PAINT ORANGE (-1750 1725);
DISPLAY INVISIBLE (-1750 1725);
FORCEPROP 2 LAST BOM_COST PROC_VRD_VCCIN_CPU0
J 0
(-1575 1725);
PAINT MONO (-1575 1725);
DISPLAY INVISIBLE (-1575 1725);
FORCEPROP 1 LAST BODY_TYPE PLUMBING
J 0
(-1245 1607);
DISPLAY 0.340426 (-1245 1607);
PAINT GREEN (-1245 1607);
DISPLAY INVISIBLE (-1245 1607);
FORCEPROP 1 LAST HDL_POWER GND
J 0
(-1200 1800);
DISPLAY 0.893617 (-1200 1800);
PAINT GREEN (-1200 1800);
DISPLAY INVISIBLE (-1200 1800);
FORCEADD CAPP..1
(-950 2050);
FORCEPROP 1 LAST PART_NUMBER A31228-047
J 0
(-900 1850);
DISPLAY 0.617021 (-900 1850);
PAINT BLUE (-900 1850);
FORCEPROP 1 LAST MATERIAL OSCON
J 0
(-900 1950);
DISPLAY 0.617021 (-900 1950);
PAINT SKYBLUE (-900 1950);
FORCEPROP 1 LAST VOLTAGE 16V
J 0
(-900 2000);
DISPLAY 0.617021 (-900 2000);
PAINT SKYBLUE (-900 2000);
FORCEPROP 1 LAST TOLERANCE 20%
J 0
(-900 2050);
DISPLAY 0.617021 (-900 2050);
PAINT SKYBLUE (-900 2050);
FORCEPROP 1 LAST PACK_TYPE 2626
J 0
(-900 1900);
DISPLAY 0.617021 (-900 1900);
PAINT SKYBLUE (-900 1900);
FORCEPROP 1 LASTPIN (-950 2150) $PN 1
J 0
(-940 2135);
DISPLAY 0.617021 (-940 2135);
PAINT ORANGE (-940 2135);
FORCEPROP 1 LASTPIN (-950 1950) $PN 2
J 0
(-940 1935);
DISPLAY 0.617021 (-940 1935);
PAINT ORANGE (-940 1935);
FORCEPROP 1 LAST VALUE 270UF
J 0
(-900 2100);
DISPLAY 0.617021 (-900 2100);
PAINT SKYBLUE (-900 2100);
FORCEPROP 1 LAST LOCATION C1E18
J 0
(-900 2150);
DISPLAY 0.617021 (-900 2150);
PAINT AQUA (-900 2150);
FORCEPROP 2 LAST ROOM PVCCIN_CPU1_FILTER_VR
J 0
(-900 2200);
DISPLAY 1.361702 (-900 2200);
PAINT ORANGE (-900 2200);
DISPLAY INVISIBLE (-900 2200);
FORCEPROP 1 LAST PATH I37
J 0
(-900 2200);
DISPLAY 0.978723 (-900 2200);
PAINT ORANGE (-900 2200);
DISPLAY INVISIBLE (-900 2200);
FORCEPROP 2 LAST SEC 1
J 0
(-900 2250);
DISPLAY 0.680851 (-900 2250);
PAINT MONO (-900 2250);
DISPLAY INVISIBLE (-900 2250);
FORCEPROP 2 LAST SEC_TYPE 2626
J 0
(-900 2250);
DISPLAY 1.021277 (-900 2250);
PAINT ORANGE (-900 2250);
DISPLAY INVISIBLE (-900 2250);
FORCEPROP 2 LAST CDS_LOCATION C1E18
J 0
(-900 2150);
DISPLAY 0.617021 (-900 2150);
PAINT AQUA (-900 2150);
DISPLAY INVISIBLE (-900 2150);
FORCEPROP 2 LAST CDS_LIB mstr_discrete
J 0
(-950 2050);
PAINT ORANGE (-950 2050);
DISPLAY INVISIBLE (-950 2050);
FORCEADD CAPP..1
(-600 2050);
FORCEPROP 1 LAST PART_NUMBER A31228-047
J 0
(-550 1850);
DISPLAY 0.617021 (-550 1850);
PAINT BLUE (-550 1850);
FORCEPROP 1 LAST MATERIAL OSCON
J 0
(-550 1950);
DISPLAY 0.617021 (-550 1950);
PAINT SKYBLUE (-550 1950);
FORCEPROP 1 LAST VOLTAGE 16V
J 0
(-550 2000);
DISPLAY 0.617021 (-550 2000);
PAINT SKYBLUE (-550 2000);
FORCEPROP 1 LAST TOLERANCE 20%
J 0
(-550 2050);
DISPLAY 0.617021 (-550 2050);
PAINT SKYBLUE (-550 2050);
FORCEPROP 1 LAST PACK_TYPE 2626
J 0
(-550 1900);
DISPLAY 0.617021 (-550 1900);
PAINT SKYBLUE (-550 1900);
FORCEPROP 1 LASTPIN (-600 1950) $PN 2
J 0
(-590 1935);
DISPLAY 0.617021 (-590 1935);
PAINT ORANGE (-590 1935);
FORCEPROP 1 LASTPIN (-600 2150) $PN 1
J 0
(-590 2135);
DISPLAY 0.617021 (-590 2135);
PAINT ORANGE (-590 2135);
FORCEPROP 1 LAST VALUE 270UF
J 0
(-550 2100);
DISPLAY 0.617021 (-550 2100);
PAINT SKYBLUE (-550 2100);
FORCEPROP 1 LAST LOCATION C1C2
J 0
(-550 2150);
DISPLAY 0.617021 (-550 2150);
PAINT AQUA (-550 2150);
FORCEPROP 2 LAST SEC 1
J 0
(-550 2250);
DISPLAY 0.680851 (-550 2250);
PAINT MONO (-550 2250);
DISPLAY INVISIBLE (-550 2250);
FORCEPROP 2 LAST SEC_TYPE 2626
J 0
(-550 2250);
DISPLAY 1.021277 (-550 2250);
PAINT ORANGE (-550 2250);
DISPLAY INVISIBLE (-550 2250);
FORCEPROP 1 LAST PATH I38
J 0
(-550 2200);
DISPLAY 0.978723 (-550 2200);
PAINT ORANGE (-550 2200);
DISPLAY INVISIBLE (-550 2200);
FORCEPROP 2 LAST ROOM PVCCIN_CPU1_FILTER_VR
J 0
(-550 2200);
DISPLAY 1.361702 (-550 2200);
PAINT ORANGE (-550 2200);
DISPLAY INVISIBLE (-550 2200);
FORCEPROP 2 LAST CDS_LIB mstr_discrete
J 0
(-600 2050);
PAINT ORANGE (-600 2050);
DISPLAY INVISIBLE (-600 2050);
FORCEPROP 2 LAST CDS_LOCATION C1C2
J 0
(-550 2150);
DISPLAY 0.617021 (-550 2150);
PAINT AQUA (-550 2150);
DISPLAY INVISIBLE (-550 2150);
FORCEADD GND..1
(-6850 3525);
FORCEPROP 3 LASTPIN (-6850 3575) SIG_NAME GND\g
J 0
(-6840 3585);
DISPLAY 0.659574 (-6840 3585);
PAINT MONO (-6840 3585);
DISPLAY INVISIBLE (-6840 3585);
FORCEPROP 2 LAST ROOM PVCCIN_CPU1_PWR_VR
J 0
(-7400 3600);
DISPLAY 1.936170 (-7400 3600);
PAINT ORANGE (-7400 3600);
DISPLAY INVISIBLE (-7400 3600);
FORCEPROP 2 LAST CDS_LIB mstr_symbols
J 0
(-6850 3525);
DISPLAY 1.936170 (-6850 3525);
PAINT ORANGE (-6850 3525);
DISPLAY INVISIBLE (-6850 3525);
FORCEPROP 1 LAST VOLTAGE 0
J 0
(-6850 3525);
PAINT SKYBLUE (-6850 3525);
DISPLAY INVISIBLE (-6850 3525);
FORCEPROP 2 LAST BOM_COST PROC_VRD_VCCIN_CPU0
J 0
(-7225 3600);
DISPLAY 1.446809 (-7225 3600);
PAINT MONO (-7225 3600);
DISPLAY INVISIBLE (-7225 3600);
FORCEPROP 1 LAST PATH I4
J 0
(-6775 3525);
DISPLAY 0.872340 (-6775 3525);
PAINT AQUA (-6775 3525);
DISPLAY INVISIBLE (-6775 3525);
FORCEPROP 1 LAST SIZE 1B
J 0
(-6775 3475);
DISPLAY 1.723404 (-6775 3475);
PAINT GREEN (-6775 3475);
DISPLAY INVISIBLE (-6775 3475);
FORCEPROP 1 LAST BODY_TYPE PLUMBING
J 0
(-6895 3482);
DISPLAY 0.340426 (-6895 3482);
PAINT GREEN (-6895 3482);
DISPLAY INVISIBLE (-6895 3482);
FORCEPROP 1 LAST HDL_POWER GND
J 0
(-6850 3675);
DISPLAY 1.723404 (-6850 3675);
PAINT GREEN (-6850 3675);
DISPLAY INVISIBLE (-6850 3675);
FORCEADD GND..1
(-350 2925);
FORCEPROP 3 LASTPIN (-350 2975) SIG_NAME GND\g
J 0
(-340 2985);
DISPLAY 0.659574 (-340 2985);
PAINT MONO (-340 2985);
DISPLAY INVISIBLE (-340 2985);
FORCEPROP 1 LAST VOLTAGE 0
J 0
(-350 2925);
PAINT SKYBLUE (-350 2925);
DISPLAY INVISIBLE (-350 2925);
FORCEPROP 2 LAST CDS_LIB mstr_symbols
J 0
(-350 2925);
DISPLAY 1.936170 (-350 2925);
PAINT ORANGE (-350 2925);
DISPLAY INVISIBLE (-350 2925);
FORCEPROP 1 LAST PATH I41
J 0
(-275 2925);
DISPLAY 0.872340 (-275 2925);
PAINT AQUA (-275 2925);
DISPLAY INVISIBLE (-275 2925);
FORCEPROP 1 LAST SIZE 1B
J 0
(-275 2875);
DISPLAY 1.723404 (-275 2875);
PAINT GREEN (-275 2875);
DISPLAY INVISIBLE (-275 2875);
FORCEPROP 2 LAST BOM_COST PROC_VRD_VCCIN_CPU0
J 0
(-725 3000);
DISPLAY 1.446809 (-725 3000);
PAINT MONO (-725 3000);
DISPLAY INVISIBLE (-725 3000);
FORCEPROP 2 LAST ROOM PVCCIN_CPU1_PWR_VR
J 0
(-900 3000);
DISPLAY 1.936170 (-900 3000);
PAINT ORANGE (-900 3000);
DISPLAY INVISIBLE (-900 3000);
FORCEPROP 1 LAST BODY_TYPE PLUMBING
J 0
(-395 2882);
DISPLAY 0.340426 (-395 2882);
PAINT GREEN (-395 2882);
DISPLAY INVISIBLE (-395 2882);
FORCEPROP 1 LAST HDL_POWER GND
J 0
(-350 3075);
DISPLAY 1.723404 (-350 3075);
PAINT GREEN (-350 3075);
DISPLAY INVISIBLE (-350 3075);
FORCEADD CAP_A..1
(-750 3250);
FORCEPROP 1 LASTPIN (-750 3150) $PN 2
J 0
(-740 3130);
DISPLAY 0.617021 (-740 3130);
PAINT GREEN (-740 3130);
FORCEPROP 1 LASTPIN (-750 3350) $PN 1
J 0
(-740 3330);
DISPLAY 0.617021 (-740 3330);
PAINT GREEN (-740 3330);
FORCEPROP 1 LAST PART_NUMBER E15431-004
J 0
(-700 3175);
DISPLAY 0.617021 (-700 3175);
PAINT BLUE (-700 3175);
FORCEPROP 1 LAST PACK_TYPE 0603V
J 0
(-700 3125);
DISPLAY 0.617021 (-700 3125);
PAINT SKYBLUE (-700 3125);
FORCEPROP 1 LAST MATERIAL X6S
J 0
(-700 3225);
DISPLAY 0.617021 (-700 3225);
PAINT SKYBLUE (-700 3225);
FORCEPROP 1 LAST TOLERANCE 20%
J 0
(-700 3275);
DISPLAY 0.617021 (-700 3275);
PAINT SKYBLUE (-700 3275);
FORCEPROP 1 LAST VOLTAGE 4V
J 0
(-700 3325);
DISPLAY 0.617021 (-700 3325);
PAINT SKYBLUE (-700 3325);
FORCEPROP 1 LAST LOCATION C1D24
J 0
(-700 3425);
DISPLAY 0.617021 (-700 3425);
PAINT AQUA (-700 3425);
FORCEPROP 1 LAST VALUE 22.0UF
J 0
(-700 3375);
DISPLAY 0.617021 (-700 3375);
PAINT SKYBLUE (-700 3375);
FORCEPROP 0 LAST GROUP PWR_MLCC_CAP
J 0
(-694 3062);
DISPLAY 0.638298 (-694 3062);
PAINT BROWN (-694 3062);
DISPLAY BOTH (-694 3062);
FORCEPROP 2 LAST CDS_LIB dev_discrete
J 0
(-750 3250);
PAINT ORANGE (-750 3250);
DISPLAY INVISIBLE (-750 3250);
FORCEPROP 2 LAST CDS_LOCATION C1D24
J 0
(-700 3350);
DISPLAY 0.617021 (-700 3350);
PAINT AQUA (-700 3350);
DISPLAY INVISIBLE (-700 3350);
FORCEPROP 2 LAST ROOM PVCCIN_CPU1_PWR_VR
J 0
(-700 3400);
DISPLAY 1.446809 (-700 3400);
PAINT MONO (-700 3400);
DISPLAY INVISIBLE (-700 3400);
FORCEPROP 1 LAST PATH I42
J 0
(-700 3400);
DISPLAY 0.978723 (-700 3400);
PAINT WHITE (-700 3400);
DISPLAY INVISIBLE (-700 3400);
FORCEPROP 2 LAST SEC 1
J 0
(-695 3450);
DISPLAY 0.680851 (-695 3450);
PAINT MONO (-695 3450);
DISPLAY INVISIBLE (-695 3450);
FORCEPROP 2 LAST SEC_TYPE 0603V
J 0
(-695 3450);
DISPLAY 1.021277 (-695 3450);
PAINT ORANGE (-695 3450);
DISPLAY INVISIBLE (-695 3450);
FORCEPROP 2 LAST CDS_SEC 1
J 0
(-700 3400);
PAINT ORANGE (-700 3400);
DISPLAY INVISIBLE (-700 3400);
FORCEPROP 2 LAST BOM_COST PROC_VRD_VCCIN_CPU0
J 0
(-700 3400);
DISPLAY 1.446809 (-700 3400);
PAINT MONO (-700 3400);
DISPLAY INVISIBLE (-700 3400);
FORCEADD PVCCIN_CPU1..1
(-350 3575);
FORCEPROP 3 LASTPIN (-350 3525) SIG_NAME PVCCIN_CPU1\g
J 0
(-340 3535);
DISPLAY 0.659574 (-340 3535);
PAINT MONO (-340 3535);
DISPLAY INVISIBLE (-340 3535);
FORCEPROP 1 LAST PATH I43
J 0
(-300 3600);
DISPLAY 0.872340 (-300 3600);
PAINT AQUA (-300 3600);
DISPLAY INVISIBLE (-300 3600);
FORCEPROP 2 LAST CDS_LIB mstr_symbols
J 0
(-350 3575);
PAINT ORANGE (-350 3575);
DISPLAY INVISIBLE (-350 3575);
FORCEPROP 1 LAST VOLTAGE 2.0V
J 0
(-395 3532);
DISPLAY 0.340426 (-395 3532);
PAINT SKYBLUE (-395 3532);
DISPLAY INVISIBLE (-395 3532);
FORCEPROP 1 LAST BODY_TYPE PLUMBING
J 0
(-395 3532);
DISPLAY 0.340426 (-395 3532);
PAINT GREEN (-395 3532);
DISPLAY INVISIBLE (-395 3532);
FORCEPROP 1 LAST HDL_POWER PVCCIN_CPU1
J 1
(-350 3625);
DISPLAY 0.872340 (-350 3625);
PAINT GREEN (-350 3625);
DISPLAY INVISIBLE (-350 3625);
FORCEADD OFFPAGE..2
(-1700 3975);
FORCEPROP 2 LAST $XR2 206 
J 0
(-1271 3975);
DISPLAY 0.638298 (-1271 3975);
PAINT MONO (-1271 3975);
FORCEPROP 2 LAST $XR1 208 
J 0
(-1391 3975);
DISPLAY 0.638298 (-1391 3975);
PAINT MONO (-1391 3975);
FORCEPROP 2 LAST $XR0 207 
J 0
(-1511 3975);
DISPLAY 0.638298 (-1511 3975);
PAINT MONO (-1511 3975);
FORCEPROP 2 LAST PATH I44
J 0
(-1270 4025);
DISPLAY 1.021277 (-1270 4025);
PAINT ORANGE (-1270 4025);
DISPLAY INVISIBLE (-1270 4025);
FORCEPROP 2 LAST BOM_COST PROC_VRD_VCCIN_CPU0
J 0
(-1500 4025);
DISPLAY 1.446809 (-1500 4025);
PAINT MONO (-1500 4025);
DISPLAY INVISIBLE (-1500 4025);
FORCEPROP 2 LAST CDS_LIB mstr_standard
J 0
(-1700 3975);
PAINT ORANGE (-1700 3975);
DISPLAY INVISIBLE (-1700 3975);
FORCEPROP 2 LAST ROOM PVCCIN_CPU1_PWR_VR
J 0
(-2100 4050);
DISPLAY 1.936170 (-2100 4050);
PAINT ORANGE (-2100 4050);
DISPLAY INVISIBLE (-2100 4050);
FORCEPROP 1 LAST OFFPAGE TRUE
J 0
(-1375 3850);
DISPLAY 1.723404 (-1375 3850);
PAINT GREEN (-1375 3850);
DISPLAY INVISIBLE (-1375 3850);
FORCEPROP 1 LAST COMMENT_BODY TRUE
J 0
(-1745 3880);
DISPLAY 1.723404 (-1745 3880);
PAINT GREEN (-1745 3880);
DISPLAY INVISIBLE (-1745 3880);
FORCEADD VCC_CORE..1
(-600 2525);
FORCEPROP 3 LASTPIN (-600 2475) SIG_NAME VR_FET_SW_P12V_STBY_PVCCIN_CPU1\g
J 0
(-590 2485);
DISPLAY 0.659574 (-590 2485);
PAINT MONO (-590 2485);
DISPLAY INVISIBLE (-590 2485);
FORCEPROP 1 LAST HDL_POWER VR_FET_SW_P12V_STBY_PVCCIN_CPU1
J 1
(-600 2575);
DISPLAY 0.617021 (-600 2575);
PAINT GREEN (-600 2575);
FORCEPROP 2 LAST CDS_LIB mstr_symbols
J 0
(-600 2525);
PAINT ORANGE (-600 2525);
DISPLAY INVISIBLE (-600 2525);
FORCEPROP 1 LAST PATH I45
J 0
(-550 2550);
DISPLAY 0.872340 (-550 2550);
PAINT AQUA (-550 2550);
DISPLAY INVISIBLE (-550 2550);
FORCEADD OFFPAGE..2
(-1150 4325);
FORCEPROP 2 LAST $XR0 206 
J 0
(-961 4325);
DISPLAY 0.638298 (-961 4325);
PAINT MONO (-961 4325);
FORCEPROP 2 LAST BOM_COST PROC_VRD_VCCIN_CPU0
J 0
(-950 4375);
DISPLAY 1.446809 (-950 4375);
PAINT MONO (-950 4375);
DISPLAY INVISIBLE (-950 4375);
FORCEPROP 2 LAST PATH I49
J 0
(-945 4375);
DISPLAY 1.021277 (-945 4375);
PAINT ORANGE (-945 4375);
DISPLAY INVISIBLE (-945 4375);
FORCEPROP 2 LAST CDS_LIB mstr_standard
J 0
(-1150 4325);
DISPLAY 1.936170 (-1150 4325);
PAINT ORANGE (-1150 4325);
DISPLAY INVISIBLE (-1150 4325);
FORCEPROP 2 LAST ROOM PVCCIN_CPU1_PWR_VR
J 0
(-1550 4400);
DISPLAY 1.936170 (-1550 4400);
PAINT ORANGE (-1550 4400);
DISPLAY INVISIBLE (-1550 4400);
FORCEPROP 1 LAST OFFPAGE TRUE
J 0
(-825 4200);
DISPLAY 1.723404 (-825 4200);
PAINT GREEN (-825 4200);
DISPLAY INVISIBLE (-825 4200);
FORCEPROP 1 LAST COMMENT_BODY TRUE
J 0
(-1195 4230);
DISPLAY 1.723404 (-1195 4230);
PAINT GREEN (-1195 4230);
DISPLAY INVISIBLE (-1195 4230);
FORCEADD CAP..1
(-7125 4025);
FORCEPROP 1 LAST PART_NUMBER C95333-007
J 0
(-7075 3875);
DISPLAY 0.617021 (-7075 3875);
PAINT BLUE (-7075 3875);
FORCEPROP 1 LAST VOLTAGE 16V
J 0
(-7075 4025);
DISPLAY 0.617021 (-7075 4025);
PAINT SKYBLUE (-7075 4025);
FORCEPROP 1 LASTPIN (-7125 4125) $PN 1
J 0
(-7115 4105);
DISPLAY 0.617021 (-7115 4105);
PAINT ORANGE (-7115 4105);
FORCEPROP 1 LAST LOCATION C9N27
J 0
(-7075 4125);
DISPLAY 0.617021 (-7075 4125);
PAINT AQUA (-7075 4125);
FORCEPROP 1 LAST VALUE 10UF
J 0
(-7075 4075);
DISPLAY 0.617021 (-7075 4075);
PAINT SKYBLUE (-7075 4075);
FORCEPROP 1 LAST MATERIAL X6S
J 0
(-7075 3925);
DISPLAY 0.617021 (-7075 3925);
PAINT SKYBLUE (-7075 3925);
FORCEPROP 1 LASTPIN (-7125 3925) $PN 2
J 0
(-7115 3905);
DISPLAY 0.617021 (-7115 3905);
PAINT ORANGE (-7115 3905);
FORCEPROP 1 LAST PACK_TYPE 0805
J 0
(-7075 3825);
DISPLAY 0.617021 (-7075 3825);
PAINT SKYBLUE (-7075 3825);
FORCEPROP 1 LAST TOLERANCE 10%
J 0
(-7075 3975);
DISPLAY 0.617021 (-7075 3975);
PAINT SKYBLUE (-7075 3975);
FORCEPROP 2 LAST CDS_LIB mstr_discrete
J 0
(-7125 4025);
PAINT ORANGE (-7125 4025);
DISPLAY INVISIBLE (-7125 4025);
FORCEPROP 2 LAST ROOM PVCCIN_CPU1_PWR_VR
J 0
(-7075 4175);
DISPLAY 1.361702 (-7075 4175);
PAINT ORANGE (-7075 4175);
DISPLAY INVISIBLE (-7075 4175);
FORCEPROP 1 LAST PATH I5
J 0
(-7075 4175);
DISPLAY 0.978723 (-7075 4175);
PAINT WHITE (-7075 4175);
DISPLAY INVISIBLE (-7075 4175);
FORCEPROP 2 LAST SEC 1
J 0
(-7075 4225);
DISPLAY 0.680851 (-7075 4225);
PAINT MONO (-7075 4225);
DISPLAY INVISIBLE (-7075 4225);
FORCEPROP 2 LAST SEC_TYPE 0805
J 0
(-7075 4225);
DISPLAY 1.021277 (-7075 4225);
PAINT ORANGE (-7075 4225);
DISPLAY INVISIBLE (-7075 4225);
FORCEADD P12V_STBY..1
(-3350 2475);
FORCEPROP 3 LASTPIN (-3350 2425) SIG_NAME P12V_STBY\g
J 0
(-3340 2435);
DISPLAY 0.659574 (-3340 2435);
PAINT MONO (-3340 2435);
DISPLAY INVISIBLE (-3340 2435);
FORCEPROP 1 LAST PATH I53
J 0
(-3305 2477);
DISPLAY 0.340426 (-3305 2477);
PAINT GREEN (-3305 2477);
DISPLAY INVISIBLE (-3305 2477);
FORCEPROP 1 LAST SIZE 1B
J 0
(-3305 2497);
DISPLAY 0.340426 (-3305 2497);
PAINT GREEN (-3305 2497);
DISPLAY INVISIBLE (-3305 2497);
FORCEPROP 2 LAST CDS_LIB mstr_symbols
J 0
(-3350 2475);
PAINT ORANGE (-3350 2475);
DISPLAY INVISIBLE (-3350 2475);
FORCEPROP 1 LAST VOLTAGE 12.0V
J 0
(-3395 2432);
DISPLAY 0.340426 (-3395 2432);
PAINT SKYBLUE (-3395 2432);
DISPLAY INVISIBLE (-3395 2432);
FORCEPROP 1 LAST BODY_TYPE PLUMBING
J 0
(-3395 2432);
DISPLAY 0.340426 (-3395 2432);
PAINT GREEN (-3395 2432);
DISPLAY INVISIBLE (-3395 2432);
FORCEPROP 1 LAST HDL_POWER P12V_STBY
J 0
(-3650 2350);
DISPLAY 0.872340 (-3650 2350);
PAINT ORANGE (-3650 2350);
DISPLAY INVISIBLE (-3650 2350);
FORCEADD P5V_STBY..1
(-4550 4750);
FORCEPROP 3 LASTPIN (-4550 4700) SIG_NAME P5V_STBY\g
J 0
(-4540 4710);
DISPLAY 0.659574 (-4540 4710);
PAINT MONO (-4540 4710);
DISPLAY INVISIBLE (-4540 4710);
FORCEPROP 1 LAST PATH I54
J 0
(-4505 4752);
DISPLAY 0.340426 (-4505 4752);
PAINT GREEN (-4505 4752);
DISPLAY INVISIBLE (-4505 4752);
FORCEPROP 2 LAST CDS_LIB mstr_symbols
J 0
(-4550 4750);
PAINT ORANGE (-4550 4750);
DISPLAY INVISIBLE (-4550 4750);
FORCEPROP 1 LAST SIZE 1B
J 0
(-4505 4772);
DISPLAY 0.340426 (-4505 4772);
PAINT GREEN (-4505 4772);
DISPLAY INVISIBLE (-4505 4772);
FORCEPROP 1 LAST VOLTAGE 5.0V
J 0
(-4595 4707);
DISPLAY 0.340426 (-4595 4707);
PAINT SKYBLUE (-4595 4707);
DISPLAY INVISIBLE (-4595 4707);
FORCEPROP 1 LAST BODY_TYPE PLUMBING
J 0
(-4595 4707);
DISPLAY 0.340426 (-4595 4707);
PAINT GREEN (-4595 4707);
DISPLAY INVISIBLE (-4595 4707);
FORCEPROP 1 LAST HDL_POWER P5V_STBY
J 0
(-4850 4625);
DISPLAY 0.872340 (-4850 4625);
PAINT ORANGE (-4850 4625);
DISPLAY INVISIBLE (-4850 4625);
FORCEADD CAP_A..1
(-350 3250);
FORCEPROP 1 LASTPIN (-350 3150) $PN 2
J 0
(-340 3130);
DISPLAY 0.617021 (-340 3130);
PAINT ORANGE (-340 3130);
FORCEPROP 1 LAST MATERIAL X6S
J 0
(-300 3225);
DISPLAY 0.617021 (-300 3225);
PAINT SKYBLUE (-300 3225);
FORCEPROP 1 LAST PACK_TYPE 0603V
J 0
(-300 3125);
DISPLAY 0.617021 (-300 3125);
PAINT SKYBLUE (-300 3125);
FORCEPROP 1 LAST VALUE 22.0UF
J 0
(-300 3375);
DISPLAY 0.617021 (-300 3375);
PAINT SKYBLUE (-300 3375);
FORCEPROP 1 LAST VOLTAGE 4V
J 0
(-300 3325);
DISPLAY 0.617021 (-300 3325);
PAINT SKYBLUE (-300 3325);
FORCEPROP 1 LAST TOLERANCE 20%
J 0
(-300 3275);
DISPLAY 0.617021 (-300 3275);
PAINT SKYBLUE (-300 3275);
FORCEPROP 1 LAST PART_NUMBER E15431-004
J 0
(-300 3175);
DISPLAY 0.617021 (-300 3175);
PAINT BLUE (-300 3175);
FORCEPROP 1 LASTPIN (-350 3350) $PN 1
J 0
(-340 3330);
DISPLAY 0.617021 (-340 3330);
PAINT ORANGE (-340 3330);
FORCEPROP 1 LAST LOCATION C9P20
J 0
(-300 3425);
DISPLAY 0.617021 (-300 3425);
PAINT AQUA (-300 3425);
FORCEPROP 0 LAST GROUP PWR_MLCC_CAP
J 0
(-294 3012);
DISPLAY 0.638298 (-294 3012);
PAINT BROWN (-294 3012);
DISPLAY BOTH (-294 3012);
FORCEPROP 2 LAST CDS_LIB dev_discrete
J 0
(-350 3250);
PAINT ORANGE (-350 3250);
DISPLAY INVISIBLE (-350 3250);
FORCEPROP 2 LAST CDS_LOCATION C9P20
J 0
(-300 3350);
DISPLAY 0.617021 (-300 3350);
PAINT AQUA (-300 3350);
DISPLAY INVISIBLE (-300 3350);
FORCEPROP 2 LAST SEC 1
J 0
(-300 3450);
DISPLAY 0.680851 (-300 3450);
PAINT MONO (-300 3450);
DISPLAY INVISIBLE (-300 3450);
FORCEPROP 2 LAST SEC_TYPE 0603V
J 0
(-300 3450);
DISPLAY 1.021277 (-300 3450);
PAINT ORANGE (-300 3450);
DISPLAY INVISIBLE (-300 3450);
FORCEPROP 2 LAST CDS_SEC 1
J 0
(-300 3400);
PAINT ORANGE (-300 3400);
DISPLAY INVISIBLE (-300 3400);
FORCEPROP 1 LAST PATH I55
J 0
(-300 3400);
DISPLAY 0.978723 (-300 3400);
PAINT WHITE (-300 3400);
DISPLAY INVISIBLE (-300 3400);
FORCEADD IR354XX..1
(-3250 3775);
FORCEPROP 2 LASTPIN (-3750 3575) $PN 39
J 2
(-3760 3585);
DISPLAY 0.617021 (-3760 3585);
PAINT ORANGE (-3760 3585);
FORCEPROP 2 LASTPIN (-3750 3425) $PN 32
J 2
(-3760 3435);
DISPLAY 0.617021 (-3760 3435);
PAINT ORANGE (-3760 3435);
FORCEPROP 2 LASTPIN (-3750 3475) $PN 33
J 2
(-3760 3485);
DISPLAY 0.617021 (-3760 3485);
PAINT ORANGE (-3760 3485);
FORCEPROP 2 LASTPIN (-3750 4125) $PN 4
J 2
(-3760 4135);
DISPLAY 0.617021 (-3760 4135);
PAINT ORANGE (-3760 4135);
FORCEPROP 2 LASTPIN (-2750 3225) $PN 5
J 0
(-2740 3235);
DISPLAY 0.617021 (-2740 3235);
PAINT ORANGE (-2740 3235);
FORCEPROP 2 LASTPIN (-3750 3825) $PN 41
J 2
(-3760 3835);
DISPLAY 0.617021 (-3760 3835);
PAINT ORANGE (-3760 3835);
FORCEPROP 2 LASTPIN (-3750 3775) $PN 6
J 2
(-3760 3785);
DISPLAY 0.617021 (-3760 3785);
PAINT ORANGE (-3760 3785);
FORCEPROP 2 LASTPIN (-3750 3925) $PN 1
J 2
(-3760 3935);
DISPLAY 0.617021 (-3760 3935);
PAINT ORANGE (-3760 3935);
FORCEPROP 2 LASTPIN (-2750 3325) $PN 40
J 0
(-2740 3335);
DISPLAY 0.617021 (-2740 3335);
PAINT ORANGE (-2740 3335);
FORCEPROP 2 LASTPIN (-2750 3475) $PN 10
J 0
(-2740 3485);
DISPLAY 0.617021 (-2740 3485);
PAINT ORANGE (-2740 3485);
FORCEPROP 2 LASTPIN (-3750 4225) $PN 25
J 2
(-3760 4235);
DISPLAY 0.617021 (-3760 4235);
PAINT ORANGE (-3760 4235);
FORCEPROP 2 LASTPIN (-3750 4275) $PN 30
J 2
(-3760 4285);
DISPLAY 0.617021 (-3760 4285);
PAINT ORANGE (-3760 4285);
FORCEPROP 2 LASTPIN (-3750 4325) $PN 3
J 2
(-3760 4335);
DISPLAY 0.617021 (-3760 4335);
PAINT ORANGE (-3760 4335);
FORCEPROP 2 LASTPIN (-3750 3675) $PN 34
J 2
(-3760 3685);
DISPLAY 0.617021 (-3760 3685);
PAINT ORANGE (-3760 3685);
FORCEPROP 2 LASTPIN (-2750 3825) $PN 36
J 0
(-2740 3835);
DISPLAY 0.617021 (-2740 3835);
PAINT ORANGE (-2740 3835);
FORCEPROP 2 LASTPIN (-2750 4125) $PN 37
J 0
(-2740 4135);
DISPLAY 0.617021 (-2740 4135);
PAINT ORANGE (-2740 4135);
FORCEPROP 2 LASTPIN (-2750 4325) $PN 38
J 0
(-2740 4335);
DISPLAY 0.617021 (-2740 4335);
PAINT ORANGE (-2740 4335);
FORCEPROP 2 LASTPIN (-2750 4075) $PN 31
J 0
(-2740 4085);
DISPLAY 0.617021 (-2740 4085);
PAINT ORANGE (-2740 4085);
FORCEPROP 2 LASTPIN (-2750 3275) $PN 7
J 0
(-2740 3285);
DISPLAY 0.617021 (-2740 3285);
PAINT ORANGE (-2740 3285);
FORCEPROP 2 LASTPIN (-2750 3375) $PN 2
J 0
(-2740 3385);
DISPLAY 0.617021 (-2740 3385);
PAINT ORANGE (-2740 3385);
FORCEPROP 1 LAST MATERIAL IC
J 0
(-3700 4525);
DISPLAY 0.617021 (-3700 4525);
PAINT SKYBLUE (-3700 4525);
FORCEPROP 1 LAST LOCATION EU1C3
J 0
(-3650 4500);
DISPLAY 0.617021 (-3650 4500);
PAINT AQUA (-3650 4500);
FORCEPROP 2 LASTPIN (-3750 4025) $PN 35
J 2
(-3760 4035);
DISPLAY 0.617021 (-3760 4035);
PAINT ORANGE (-3760 4035);
FORCEPROP 1 LAST PART_NUMBER H73688-001
J 0
(-3650 3050);
DISPLAY 0.617021 (-3650 3050);
PAINT BLUE (-3650 3050);
FORCEPROP 2 LAST CDS_LIB mstr_discrete
J 0
(-3250 3775);
PAINT ORANGE (-3250 3775);
DISPLAY INVISIBLE (-3250 3775);
FORCEPROP 2 LAST CDS_LOCATION EU1C3
J 0
(-3650 4500);
DISPLAY 0.617021 (-3650 4500);
PAINT AQUA (-3650 4500);
DISPLAY INVISIBLE (-3650 4500);
FORCEPROP 2 LAST ROOM PVCCIN_CPU1_PWR_VR
J 0
(-3650 4550);
DISPLAY 1.361702 (-3650 4550);
PAINT ORANGE (-3650 4550);
DISPLAY INVISIBLE (-3650 4550);
FORCEPROP 1 LAST PACK_TYPE SM
J 0
(-3700 4625);
PAINT SKYBLUE (-3700 4625);
DISPLAY INVISIBLE (-3700 4625);
FORCEPROP 1 LAST PATH I56
J 0
(-3250 4525);
PAINT GREEN (-3250 4525);
DISPLAY INVISIBLE (-3250 4525);
FORCEPROP 2 LAST SEC 1
J 0
(-3250 4575);
DISPLAY 0.680851 (-3250 4575);
PAINT MONO (-3250 4575);
DISPLAY INVISIBLE (-3250 4575);
FORCEPROP 2 LAST SEC_TYPE SM
J 0
(-3250 4575);
DISPLAY 1.021277 (-3250 4575);
PAINT ORANGE (-3250 4575);
DISPLAY INVISIBLE (-3250 4575);
FORCEPROP 1 LAST VALUE IR35411
J 1
(-3250 4400);
DISPLAY 0.617021 (-3250 4400);
PAINT SKYBLUE (-3250 4400);
DISPLAY INVISIBLE (-3250 4400);
FORCEADD OFFPAGE..1
(-6225 3675);
FORCEPROP 2 LASTPIN (-6175 3675) SIG_NAME VR_PVCCIN_CPU1_PWM5
J 0
(-6160 3685);
DISPLAY 0.617021 (-6160 3685);
PAINT ORANGE (-6160 3685);
FORCEPROP 2 LAST $XR0 206 
J 0
(-6477 3675);
DISPLAY 0.638298 (-6477 3675);
PAINT MONO (-6477 3675);
FORCEPROP 2 LAST CDS_LIB mstr_standard
J 0
(-6225 3675);
DISPLAY 1.936170 (-6225 3675);
PAINT ORANGE (-6225 3675);
DISPLAY INVISIBLE (-6225 3675);
FORCEPROP 2 LAST PATH I57
J 0
(-6475 3725);
DISPLAY 1.021277 (-6475 3725);
PAINT ORANGE (-6475 3725);
DISPLAY INVISIBLE (-6475 3725);
FORCEPROP 2 LAST ROOM PVCCIN_CPU1_PWR_VR
J 0
(-6625 3750);
DISPLAY 1.936170 (-6625 3750);
PAINT ORANGE (-6625 3750);
DISPLAY INVISIBLE (-6625 3750);
FORCEPROP 2 LAST BOM_COST PROC_VRD_VCCIN_CPU0
J 0
(-6475 3725);
DISPLAY 1.446809 (-6475 3725);
PAINT MONO (-6475 3725);
DISPLAY INVISIBLE (-6475 3725);
FORCEPROP 1 LAST OFFPAGE TRUE
J 0
(-5900 3550);
DISPLAY 1.680851 (-5900 3550);
PAINT GREEN (-5900 3550);
DISPLAY INVISIBLE (-5900 3550);
FORCEPROP 1 LAST COMMENT_BODY TRUE
J 0
(-6100 3575);
DISPLAY 1.680851 (-6100 3575);
PAINT GREEN (-6100 3575);
DISPLAY INVISIBLE (-6100 3575);
FORCEADD OFFPAGE..4
(-1125 4800);
FORCEPROP 2 LAST $XR0 206 
J 0
(-939 4800);
DISPLAY 0.638298 (-939 4800);
PAINT MONO (-939 4800);
FORCEPROP 2 LAST PATH I58
J 0
(-925 4850);
DISPLAY 1.021277 (-925 4850);
PAINT ORANGE (-925 4850);
DISPLAY INVISIBLE (-925 4850);
FORCEPROP 2 LAST BOM_COST PROC_VRD_VCCIN_CPU0
J 0
(-925 4850);
DISPLAY 1.446809 (-925 4850);
PAINT MONO (-925 4850);
DISPLAY INVISIBLE (-925 4850);
FORCEPROP 2 LAST CDS_LIB mstr_standard
J 2
(-1125 4800);
DISPLAY 1.936170 (-1125 4800);
PAINT ORANGE (-1125 4800);
DISPLAY INVISIBLE (-1125 4800);
FORCEPROP 2 LAST ROOM PVCCIN_CPU1_PWR_VR
J 0
(-1525 4875);
DISPLAY 1.936170 (-1525 4875);
PAINT ORANGE (-1525 4875);
DISPLAY INVISIBLE (-1525 4875);
FORCEPROP 1 LAST OFFPAGE TRUE
J 0
(-800 4675);
DISPLAY 0.872340 (-800 4675);
PAINT GREEN (-800 4675);
DISPLAY INVISIBLE (-800 4675);
FORCEPROP 1 LAST COMMENT_BODY TRUE
J 0
(-1150 4700);
DISPLAY 0.872340 (-1150 4700);
PAINT GREEN (-1150 4700);
DISPLAY INVISIBLE (-1150 4700);
FORCEADD RES..2
(-1000 3925);
FORCEPROP 1 LAST PART_NUMBER G21796-187
J 0
(-960 3800);
DISPLAY 0.617021 (-960 3800);
PAINT BLUE (-960 3800);
FORCEPROP 1 LASTPIN (-1000 3825) $PN 2
J 0
(-995 3835);
DISPLAY 0.617021 (-995 3835);
PAINT ORANGE (-995 3835);
FORCEPROP 1 LAST LOCATION R1D52
J 0
(-955 4050);
DISPLAY 0.617021 (-955 4050);
PAINT AQUA (-955 4050);
FORCEPROP 1 LAST VALUE 68.1K
J 0
(-955 4000);
DISPLAY 0.617021 (-955 4000);
PAINT SKYBLUE (-955 4000);
FORCEPROP 1 LASTPIN (-1000 4025) $PN 1
J 0
(-995 3987);
DISPLAY 0.617021 (-995 3987);
PAINT ORANGE (-995 3987);
FORCEPROP 1 LAST TOLERANCE 1%
J 0
(-955 3950);
DISPLAY 0.617021 (-955 3950);
PAINT SKYBLUE (-955 3950);
FORCEPROP 1 LAST WATTAGE 1/16W
J 0
(-960 3900);
DISPLAY 0.617021 (-960 3900);
PAINT SKYBLUE (-960 3900);
FORCEPROP 1 LAST MATERIAL EMPTY
J 0
(-960 3850);
DISPLAY 0.617021 (-960 3850);
PAINT RED (-960 3850);
FORCEPROP 1 LAST PACK_TYPE 0402
J 0
(-960 3750);
DISPLAY 0.617021 (-960 3750);
PAINT SKYBLUE (-960 3750);
FORCEPROP 1 LAST PATH I59
J 0
(-950 4100);
DISPLAY 0.978723 (-950 4100);
PAINT WHITE (-950 4100);
DISPLAY INVISIBLE (-950 4100);
FORCEPROP 2 LAST $SEC 1
J 0
(-950 4150);
PAINT MONO (-950 4150);
DISPLAY INVISIBLE (-950 4150);
FORCEPROP 2 LAST CDS_SEC 1
J 0
(-950 4150);
PAINT MONO (-950 4150);
DISPLAY INVISIBLE (-950 4150);
FORCEPROP 2 LAST CDS_LIB mstr_discrete
J 0
(-1000 3925);
PAINT ORANGE (-1000 3925);
DISPLAY INVISIBLE (-1000 3925);
FORCEADD GND..1
(-1000 3750);
FORCEPROP 3 LASTPIN (-1000 3800) SIG_NAME GND\g
J 0
(-990 3810);
DISPLAY 0.659574 (-990 3810);
PAINT MONO (-990 3810);
DISPLAY INVISIBLE (-990 3810);
FORCEPROP 2 LAST ROOM PVCCIN_CPU1_FILTER_VR
J 0
(-1550 3825);
PAINT ORANGE (-1550 3825);
DISPLAY INVISIBLE (-1550 3825);
FORCEPROP 2 LAST BOM_COST PROC_VRD_VCCIN_CPU0
J 0
(-1375 3825);
PAINT MONO (-1375 3825);
DISPLAY INVISIBLE (-1375 3825);
FORCEPROP 1 LAST PATH I60
J 0
(-925 3750);
DISPLAY 0.872340 (-925 3750);
PAINT AQUA (-925 3750);
DISPLAY INVISIBLE (-925 3750);
FORCEPROP 1 LAST SIZE 1B
J 0
(-925 3700);
DISPLAY 0.893617 (-925 3700);
PAINT GREEN (-925 3700);
DISPLAY INVISIBLE (-925 3700);
FORCEPROP 2 LAST CDS_LIB mstr_symbols
J 0
(-1000 3750);
PAINT ORANGE (-1000 3750);
DISPLAY INVISIBLE (-1000 3750);
FORCEPROP 1 LAST VOLTAGE 0
J 0
(-1000 3750);
PAINT SKYBLUE (-1000 3750);
DISPLAY INVISIBLE (-1000 3750);
FORCEPROP 1 LAST BODY_TYPE PLUMBING
J 0
(-1045 3707);
DISPLAY 0.340426 (-1045 3707);
PAINT GREEN (-1045 3707);
DISPLAY INVISIBLE (-1045 3707);
FORCEPROP 1 LAST HDL_POWER GND
J 0
(-1000 3900);
DISPLAY 0.893617 (-1000 3900);
PAINT GREEN (-1000 3900);
DISPLAY INVISIBLE (-1000 3900);
FORCEADD CAP_A..1
(-3950 3275);
FORCEPROP 1 LAST LOCATION CT13
J 0
(-4100 3275);
DISPLAY 0.617021 (-4100 3275);
PAINT AQUA (-4100 3275);
FORCEPROP 1 LAST PART_NUMBER A36096-030
J 0
(-3900 3125);
DISPLAY 0.617021 (-3900 3125);
PAINT BLUE (-3900 3125);
FORCEPROP 1 LAST PACK_TYPE 0402V
J 0
(-3900 3075);
DISPLAY 0.617021 (-3900 3075);
PAINT SKYBLUE (-3900 3075);
FORCEPROP 0 LAST POP NOPOP
J 0
(-3915 3019);
DISPLAY 1.021277 (-3915 3019);
PAINT RED (-3915 3019);
FORCEPROP 1 LAST VALUE 0.1UF
J 0
(-3900 3325);
DISPLAY 0.617021 (-3900 3325);
PAINT SKYBLUE (-3900 3325);
FORCEPROP 1 LASTPIN (-3950 3175) $PN 2
J 0
(-3940 3155);
DISPLAY 0.787234 (-3940 3155);
PAINT ORANGE (-3940 3155);
FORCEPROP 1 LAST TOLERANCE 10%
J 0
(-3900 3225);
DISPLAY 0.617021 (-3900 3225);
PAINT SKYBLUE (-3900 3225);
FORCEPROP 1 LASTPIN (-3950 3375) $PN 1
J 0
(-3940 3355);
DISPLAY 0.787234 (-3940 3355);
PAINT ORANGE (-3940 3355);
FORCEPROP 1 LAST VOLTAGE 16V
J 0
(-3900 3275);
DISPLAY 0.617021 (-3900 3275);
PAINT SKYBLUE (-3900 3275);
FORCEPROP 1 LAST MATERIAL X7R
J 0
(-3900 3175);
DISPLAY 0.617021 (-3900 3175);
PAINT SKYBLUE (-3900 3175);
FORCEPROP 2 LAST SEC_TYPE 0402V
J 0
(-3900 3475);
DISPLAY 1.021277 (-3900 3475);
PAINT ORANGE (-3900 3475);
DISPLAY INVISIBLE (-3900 3475);
FORCEPROP 0 LAST SEC 1
J 0
(-3900 3375);
DISPLAY 0.680851 (-3900 3375);
PAINT MONO (-3900 3375);
DISPLAY INVISIBLE (-3900 3375);
FORCEPROP 2 LAST CDS_LIB dev_discrete
J 0
(-3950 3275);
PAINT MONO (-3950 3275);
DISPLAY INVISIBLE (-3950 3275);
FORCEPROP 1 LAST PATH I62
J 0
(-3900 3425);
DISPLAY 0.978723 (-3900 3425);
PAINT WHITE (-3900 3425);
DISPLAY INVISIBLE (-3900 3425);
FORCEPROP 2 LAST ROOM PVCCIN_CPU0_PWR_VR
J 0
(-3900 3425);
DISPLAY 1.361702 (-3900 3425);
PAINT ORANGE (-3900 3425);
DISPLAY INVISIBLE (-3900 3425);
FORCEADD GND..1
(-3950 3025);
FORCEPROP 3 LASTPIN (-3950 3075) SIG_NAME GND\g
J 0
(-3940 3085);
DISPLAY 0.659574 (-3940 3085);
PAINT MONO (-3940 3085);
DISPLAY INVISIBLE (-3940 3085);
FORCEPROP 2 LAST CDS_LIB mstr_symbols
J 0
(-3950 3025);
PAINT MONO (-3950 3025);
DISPLAY INVISIBLE (-3950 3025);
FORCEPROP 1 LAST PATH I63
J 0
(-3875 3025);
DISPLAY 0.872340 (-3875 3025);
PAINT AQUA (-3875 3025);
DISPLAY INVISIBLE (-3875 3025);
FORCEPROP 1 LAST VOLTAGE 0
J 0
(-3950 3025);
PAINT SKYBLUE (-3950 3025);
DISPLAY INVISIBLE (-3950 3025);
FORCEPROP 1 LAST SIZE 1B
J 0
(-3875 2975);
DISPLAY 1.723404 (-3875 2975);
PAINT GREEN (-3875 2975);
DISPLAY INVISIBLE (-3875 2975);
FORCEPROP 2 LAST BOM_COST PROC_VRD_VCCIN_CPU0
J 0
(-4325 3100);
DISPLAY 1.446809 (-4325 3100);
PAINT MONO (-4325 3100);
DISPLAY INVISIBLE (-4325 3100);
FORCEPROP 2 LAST ROOM PVCCIN_CPU0_PWR_VR
J 0
(-4500 3100);
DISPLAY 1.936170 (-4500 3100);
PAINT ORANGE (-4500 3100);
DISPLAY INVISIBLE (-4500 3100);
FORCEPROP 1 LAST BODY_TYPE PLUMBING
J 0
(-3995 2982);
DISPLAY 0.340426 (-3995 2982);
PAINT GREEN (-3995 2982);
DISPLAY INVISIBLE (-3995 2982);
FORCEPROP 1 LAST HDL_POWER GND
J 0
(-3950 3175);
DISPLAY 1.723404 (-3950 3175);
PAINT GREEN (-3950 3175);
DISPLAY INVISIBLE (-3950 3175);
FORCEADD GND..1
(-2400 2800);
FORCEPROP 3 LASTPIN (-2400 2850) SIG_NAME GND\g
J 0
(-2390 2860);
DISPLAY 0.659574 (-2390 2860);
PAINT MONO (-2390 2860);
DISPLAY INVISIBLE (-2390 2860);
FORCEPROP 2 LAST CDS_LIB mstr_symbols
J 0
(-2400 2800);
PAINT MONO (-2400 2800);
DISPLAY INVISIBLE (-2400 2800);
FORCEPROP 1 LAST PATH I65
J 0
(-2325 2800);
DISPLAY 0.872340 (-2325 2800);
PAINT AQUA (-2325 2800);
DISPLAY INVISIBLE (-2325 2800);
FORCEPROP 1 LAST SIZE 1B
J 0
(-2325 2750);
DISPLAY 1.723404 (-2325 2750);
PAINT GREEN (-2325 2750);
DISPLAY INVISIBLE (-2325 2750);
FORCEPROP 1 LAST VOLTAGE 0
J 0
(-2400 2800);
PAINT SKYBLUE (-2400 2800);
DISPLAY INVISIBLE (-2400 2800);
FORCEPROP 2 LAST BOM_COST PROC_VRD_VCCIN_CPU0
J 0
(-2775 2875);
DISPLAY 1.446809 (-2775 2875);
PAINT MONO (-2775 2875);
DISPLAY INVISIBLE (-2775 2875);
FORCEPROP 2 LAST ROOM PVCCIN_CPU0_PWR_VR
J 0
(-2950 2875);
DISPLAY 1.936170 (-2950 2875);
PAINT ORANGE (-2950 2875);
DISPLAY INVISIBLE (-2950 2875);
FORCEPROP 1 LAST BODY_TYPE PLUMBING
J 0
(-2445 2757);
DISPLAY 0.340426 (-2445 2757);
PAINT GREEN (-2445 2757);
DISPLAY INVISIBLE (-2445 2757);
FORCEPROP 1 LAST HDL_POWER GND
J 0
(-2400 2950);
DISPLAY 1.723404 (-2400 2950);
PAINT GREEN (-2400 2950);
DISPLAY INVISIBLE (-2400 2950);
FORCEADD CAP..1
(-1950 3825);
FORCEPROP 1 LASTPIN (-1950 3925) $PN 1
J 0
(-1940 3905);
DISPLAY 0.787234 (-1940 3905);
PAINT ORANGE (-1940 3905);
FORCEPROP 1 LAST VALUE 1000PF
J 0
(-1900 3875);
DISPLAY 0.617021 (-1900 3875);
PAINT SKYBLUE (-1900 3875);
FORCEPROP 1 LASTPIN (-1950 3725) $PN 2
J 0
(-1940 3705);
DISPLAY 0.787234 (-1940 3705);
PAINT ORANGE (-1940 3705);
FORCEPROP 0 LAST POP NOPOP
J 0
(-2175 3725);
DISPLAY 1.021277 (-2175 3725);
PAINT RED (-2175 3725);
FORCEPROP 1 LAST LOCATION CT15
J 0
(-2100 3825);
DISPLAY 0.617021 (-2100 3825);
PAINT AQUA (-2100 3825);
FORCEPROP 1 LAST TOLERANCE 10%
J 0
(-1900 3775);
DISPLAY 0.617021 (-1900 3775);
PAINT SKYBLUE (-1900 3775);
FORCEPROP 1 LAST MATERIAL X7R
J 0
(-1900 3725);
DISPLAY 0.617021 (-1900 3725);
PAINT SKYBLUE (-1900 3725);
FORCEPROP 1 LAST PART_NUMBER A36096-046
J 0
(-1900 3675);
DISPLAY 0.617021 (-1900 3675);
PAINT BLUE (-1900 3675);
FORCEPROP 1 LAST PACK_TYPE 0402LF
J 0
(-1900 3625);
DISPLAY 0.617021 (-1900 3625);
PAINT SKYBLUE (-1900 3625);
FORCEPROP 1 LAST VOLTAGE 50V
J 0
(-1900 3825);
DISPLAY 0.617021 (-1900 3825);
PAINT SKYBLUE (-1900 3825);
FORCEPROP 2 LAST SEC_TYPE 0402LF
J 0
(-1900 4025);
DISPLAY 1.021277 (-1900 4025);
PAINT ORANGE (-1900 4025);
DISPLAY INVISIBLE (-1900 4025);
FORCEPROP 0 LAST SEC 1
J 0
(-1900 3925);
DISPLAY 0.680851 (-1900 3925);
PAINT MONO (-1900 3925);
DISPLAY INVISIBLE (-1900 3925);
FORCEPROP 2 LAST CDS_LIB mstr_discrete
J 0
(-1950 3825);
PAINT MONO (-1950 3825);
DISPLAY INVISIBLE (-1950 3825);
FORCEPROP 1 LAST PATH I67
J 0
(-1900 3975);
DISPLAY 0.978723 (-1900 3975);
PAINT WHITE (-1900 3975);
DISPLAY INVISIBLE (-1900 3975);
FORCEPROP 0 LAST ROOM VDDQ_KLM_PWR_VR
J 0
(-1900 4025);
DISPLAY 1.021277 (-1900 4025);
PAINT ORANGE (-1900 4025);
DISPLAY INVISIBLE (-1900 4025);
FORCEADD GND..1
(-1950 3575);
FORCEPROP 3 LASTPIN (-1950 3625) SIG_NAME GND\g
J 0
(-1940 3635);
DISPLAY 0.659574 (-1940 3635);
PAINT MONO (-1940 3635);
DISPLAY INVISIBLE (-1940 3635);
FORCEPROP 2 LAST CDS_LIB mstr_symbols
J 0
(-1950 3575);
PAINT MONO (-1950 3575);
DISPLAY INVISIBLE (-1950 3575);
FORCEPROP 1 LAST PATH I68
J 0
(-1875 3575);
DISPLAY 0.872340 (-1875 3575);
PAINT AQUA (-1875 3575);
DISPLAY INVISIBLE (-1875 3575);
FORCEPROP 1 LAST SIZE 1B
J 0
(-1875 3525);
DISPLAY 1.170213 (-1875 3525);
PAINT AQUA (-1875 3525);
DISPLAY INVISIBLE (-1875 3525);
FORCEPROP 1 LAST VOLTAGE 0
J 0
(-1950 3575);
PAINT SKYBLUE (-1950 3575);
DISPLAY INVISIBLE (-1950 3575);
FORCEPROP 2 LAST ROOM VDDQ_KLM_PWR_VR
J 0
(-2525 3650);
DISPLAY 1.361702 (-2525 3650);
PAINT ORANGE (-2525 3650);
DISPLAY INVISIBLE (-2525 3650);
FORCEPROP 1 LAST BODY_TYPE PLUMBING
J 0
(-1995 3532);
DISPLAY 0.340426 (-1995 3532);
PAINT GREEN (-1995 3532);
DISPLAY INVISIBLE (-1995 3532);
FORCEPROP 1 LAST HDL_POWER GND
J 0
(-1950 3725);
DISPLAY 1.170213 (-1950 3725);
PAINT GREEN (-1950 3725);
DISPLAY INVISIBLE (-1950 3725);
FORCEADD CAP..1
(-6850 4025);
FORCEPROP 1 LAST LOCATION C9N26
J 0
(-6800 4125);
DISPLAY 0.617021 (-6800 4125);
PAINT AQUA (-6800 4125);
FORCEPROP 1 LAST VALUE 10UF
J 0
(-6800 4075);
DISPLAY 0.617021 (-6800 4075);
PAINT SKYBLUE (-6800 4075);
FORCEPROP 1 LAST VOLTAGE 16V
J 0
(-6800 4025);
DISPLAY 0.617021 (-6800 4025);
PAINT SKYBLUE (-6800 4025);
FORCEPROP 1 LAST PART_NUMBER C95333-007
J 0
(-6800 3875);
DISPLAY 0.617021 (-6800 3875);
PAINT BLUE (-6800 3875);
FORCEPROP 1 LASTPIN (-6850 3925) $PN 2
J 0
(-6840 3905);
DISPLAY 0.617021 (-6840 3905);
PAINT ORANGE (-6840 3905);
FORCEPROP 1 LASTPIN (-6850 4125) $PN 1
J 0
(-6840 4105);
DISPLAY 0.617021 (-6840 4105);
PAINT ORANGE (-6840 4105);
FORCEPROP 1 LAST PACK_TYPE 0805
J 0
(-6800 3825);
DISPLAY 0.617021 (-6800 3825);
PAINT SKYBLUE (-6800 3825);
FORCEPROP 1 LAST MATERIAL X6S
J 0
(-6800 3925);
DISPLAY 0.617021 (-6800 3925);
PAINT SKYBLUE (-6800 3925);
FORCEPROP 1 LAST TOLERANCE 10%
J 0
(-6800 3975);
DISPLAY 0.617021 (-6800 3975);
PAINT SKYBLUE (-6800 3975);
FORCEPROP 2 LAST CDS_LIB mstr_discrete
J 0
(-6850 4025);
PAINT ORANGE (-6850 4025);
DISPLAY INVISIBLE (-6850 4025);
FORCEPROP 2 LAST ROOM PVCCIN_CPU1_PWR_VR
J 0
(-6800 4175);
DISPLAY 1.361702 (-6800 4175);
PAINT ORANGE (-6800 4175);
DISPLAY INVISIBLE (-6800 4175);
FORCEPROP 1 LAST PATH I7
J 0
(-6800 4175);
DISPLAY 0.978723 (-6800 4175);
PAINT WHITE (-6800 4175);
DISPLAY INVISIBLE (-6800 4175);
FORCEPROP 2 LAST SEC 1
J 0
(-6800 4225);
DISPLAY 0.680851 (-6800 4225);
PAINT MONO (-6800 4225);
DISPLAY INVISIBLE (-6800 4225);
FORCEPROP 2 LAST SEC_TYPE 0805
J 0
(-6800 4225);
DISPLAY 1.021277 (-6800 4225);
PAINT ORANGE (-6800 4225);
DISPLAY INVISIBLE (-6800 4225);
FORCEADD CAP..1
(-2400 3300);
FORCEPROP 1 LAST TOLERANCE 10%
J 0
(-2350 3250);
DISPLAY 0.617021 (-2350 3250);
PAINT SKYBLUE (-2350 3250);
FORCEPROP 1 LAST VALUE 1000PF
J 0
(-2350 3350);
DISPLAY 0.617021 (-2350 3350);
PAINT SKYBLUE (-2350 3350);
FORCEPROP 1 LASTPIN (-2400 3400) $PN 1
J 0
(-2390 3380);
DISPLAY 0.787234 (-2390 3380);
PAINT ORANGE (-2390 3380);
FORCEPROP 1 LAST LOCATION CT14
J 0
(-2350 3400);
DISPLAY 0.617021 (-2350 3400);
PAINT AQUA (-2350 3400);
FORCEPROP 1 LAST PART_NUMBER A36096-046
J 0
(-2175 3400);
DISPLAY 0.617021 (-2175 3400);
PAINT BLUE (-2175 3400);
FORCEPROP 1 LAST PACK_TYPE 0402LF
J 0
(-2175 3350);
DISPLAY 0.617021 (-2175 3350);
PAINT SKYBLUE (-2175 3350);
FORCEPROP 0 LAST POP NOPOP
J 0
(-2175 3300);
DISPLAY 0.808511 (-2175 3300);
PAINT RED (-2175 3300);
FORCEPROP 1 LAST VOLTAGE 50V
J 0
(-2350 3300);
DISPLAY 0.617021 (-2350 3300);
PAINT SKYBLUE (-2350 3300);
FORCEPROP 1 LAST MATERIAL X7R
J 0
(-2200 3250);
DISPLAY 0.617021 (-2200 3250);
PAINT SKYBLUE (-2200 3250);
FORCEPROP 1 LASTPIN (-2400 3200) $PN 2
J 0
(-2390 3180);
DISPLAY 0.787234 (-2390 3180);
PAINT ORANGE (-2390 3180);
FORCEPROP 2 LAST SEC_TYPE 0402LF
J 0
(-2350 3500);
DISPLAY 1.021277 (-2350 3500);
PAINT ORANGE (-2350 3500);
DISPLAY INVISIBLE (-2350 3500);
FORCEPROP 0 LAST SEC 1
J 0
(-2350 3450);
DISPLAY 0.680851 (-2350 3450);
PAINT MONO (-2350 3450);
DISPLAY INVISIBLE (-2350 3450);
FORCEPROP 0 LAST ROOM VDDQ_KLM_PWR_VR
J 0
(-2350 3500);
DISPLAY 1.021277 (-2350 3500);
PAINT ORANGE (-2350 3500);
DISPLAY INVISIBLE (-2350 3500);
FORCEPROP 1 LAST PATH I73
J 0
(-2350 3450);
DISPLAY 0.978723 (-2350 3450);
PAINT WHITE (-2350 3450);
DISPLAY INVISIBLE (-2350 3450);
FORCEPROP 2 LAST CDS_LIB mstr_discrete
J 0
(-2400 3300);
PAINT MONO (-2400 3300);
DISPLAY INVISIBLE (-2400 3300);
FORCEADD RES..1
(-4800 3575);
FORCEPROP 1 LAST TOLERANCE 5.0%
J 0
(-4525 3500);
DISPLAY 0.617021 (-4525 3500);
PAINT SKYBLUE (-4525 3500);
FORCEPROP 1 LAST PART_NUMBER G22178-002
J 0
(-4825 3500);
DISPLAY 0.617021 (-4825 3500);
PAINT BLUE (-4825 3500);
FORCEPROP 1 LAST PACK_TYPE 0603
J 0
(-4750 3450);
DISPLAY 0.617021 (-4750 3450);
PAINT SKYBLUE (-4750 3450);
FORCEPROP 1 LASTPIN (-4900 3575) $PN 1
J 0
(-4888 3587);
DISPLAY 0.787234 (-4888 3587);
PAINT ORANGE (-4888 3587);
FORCEPROP 1 LASTPIN (-4700 3575) $PN 2
J 0
(-4738 3587);
DISPLAY 0.787234 (-4738 3587);
PAINT ORANGE (-4738 3587);
FORCEPROP 1 LAST WATTAGE 1/10W
J 2
(-4400 3400);
DISPLAY 0.617021 (-4400 3400);
PAINT SKYBLUE (-4400 3400);
FORCEPROP 1 LAST MATERIAL CHIP
J 0
(-4525 3450);
DISPLAY 0.617021 (-4525 3450);
PAINT SKYBLUE (-4525 3450);
FORCEPROP 1 LAST LOCATION RT9
J 0
(-4950 3500);
DISPLAY 0.617021 (-4950 3500);
PAINT AQUA (-4950 3500);
FORCEPROP 1 LAST VALUE 0
J 2
(-4825 3450);
DISPLAY 0.617021 (-4825 3450);
PAINT SKYBLUE (-4825 3450);
FORCEPROP 2 LAST SEC_TYPE 0603
J 0
(-4850 3775);
DISPLAY 1.021277 (-4850 3775);
PAINT ORANGE (-4850 3775);
DISPLAY INVISIBLE (-4850 3775);
FORCEPROP 0 LAST SEC 1
J 0
(-5050 3675);
DISPLAY 0.680851 (-5050 3675);
PAINT MONO (-5050 3675);
DISPLAY INVISIBLE (-5050 3675);
FORCEPROP 0 LAST ROOM NIC_SPRV
J 0
(-4700 3700);
DISPLAY 1.021277 (-4700 3700);
PAINT ORANGE (-4700 3700);
DISPLAY INVISIBLE (-4700 3700);
FORCEPROP 0 LAST BOM_COST NT_GBE_BASE
J 0
(-4700 3800);
DISPLAY 1.021277 (-4700 3800);
PAINT ORANGE (-4700 3800);
DISPLAY INVISIBLE (-4700 3800);
FORCEPROP 1 LAST PATH I75
J 0
(-4850 3725);
DISPLAY 0.978723 (-4850 3725);
PAINT WHITE (-4850 3725);
DISPLAY INVISIBLE (-4850 3725);
FORCEPROP 2 LAST CDS_LIB mstr_discrete
J 0
(-4800 3575);
PAINT MONO (-4800 3575);
DISPLAY INVISIBLE (-4800 3575);
FORCEADD RES..1
(-5425 4650);
FORCEPROP 1 LAST WATTAGE 1/16W
J 0
(-5400 4600);
DISPLAY 0.638298 (-5400 4600);
PAINT SKYBLUE (-5400 4600);
FORCEPROP 1 LAST PACK_TYPE 0402
J 0
(-5400 4550);
DISPLAY 0.617021 (-5400 4550);
PAINT SKYBLUE (-5400 4550);
FORCEPROP 1 LAST PART_NUMBER G21497-005
J 0
(-5550 4450);
DISPLAY 0.617021 (-5550 4450);
PAINT BLUE (-5550 4450);
FORCEPROP 1 LAST MATERIAL CHIP
J 0
(-5400 4500);
DISPLAY 0.510638 (-5400 4500);
PAINT SKYBLUE (-5400 4500);
FORCEPROP 1 LAST LOCATION R9P32
J 0
(-5550 4600);
DISPLAY 0.617021 (-5550 4600);
PAINT AQUA (-5550 4600);
FORCEPROP 1 LAST TOLERANCE 5%
J 0
(-5550 4500);
DISPLAY 0.617021 (-5550 4500);
PAINT SKYBLUE (-5550 4500);
FORCEPROP 1 LAST VALUE 0.0
J 0
(-5550 4550);
DISPLAY 0.617021 (-5550 4550);
PAINT SKYBLUE (-5550 4550);
FORCEPROP 1 LASTPIN (-5525 4650) $PN 1
J 0
(-5513 4662);
DISPLAY 0.617021 (-5513 4662);
PAINT WHITE (-5513 4662);
FORCEPROP 1 LASTPIN (-5325 4650) $PN 2
J 0
(-5363 4662);
DISPLAY 0.617021 (-5363 4662);
PAINT WHITE (-5363 4662);
FORCEPROP 2 LAST CDS_LOCATION R9P32
J 0
(-5900 4650);
DISPLAY 0.617021 (-5900 4650);
PAINT AQUA (-5900 4650);
DISPLAY INVISIBLE (-5900 4650);
FORCEPROP 1 LAST PATH I79
J 0
(-5475 4800);
DISPLAY 0.978723 (-5475 4800);
PAINT WHITE (-5475 4800);
DISPLAY INVISIBLE (-5475 4800);
FORCEPROP 0 LAST CDS_SEC 1
J 0
(-5125 4700);
PAINT MONO (-5125 4700);
DISPLAY INVISIBLE (-5125 4700);
FORCEPROP 2 LAST ROOM CPU0
J 0
(-5475 4800);
PAINT PEACH (-5475 4800);
DISPLAY INVISIBLE (-5475 4800);
FORCEPROP 2 LAST SEC 1
J 0
(-5475 4875);
DISPLAY 0.680851 (-5475 4875);
PAINT MONO (-5475 4875);
DISPLAY INVISIBLE (-5475 4875);
FORCEPROP 2 LAST SEC_TYPE 0402
J 0
(-5475 4875);
DISPLAY 1.021277 (-5475 4875);
PAINT ORANGE (-5475 4875);
DISPLAY INVISIBLE (-5475 4875);
FORCEPROP 2 LAST CDS_LIB mstr_discrete
J 0
(-5425 4650);
DISPLAY 1.340426 (-5425 4650);
PAINT ORANGE (-5425 4650);
DISPLAY INVISIBLE (-5425 4650);
FORCEPROP 2 LAST BOM_COST PROC_SIDEBAND
J 0
(-5425 4650);
PAINT MONO (-5425 4650);
DISPLAY INVISIBLE (-5425 4650);
FORCEADD CAP..1
(-6550 4025);
FORCEPROP 1 LAST PART_NUMBER C95333-007
J 0
(-6500 3875);
DISPLAY 0.617021 (-6500 3875);
PAINT BLUE (-6500 3875);
FORCEPROP 1 LAST PACK_TYPE 0805
J 0
(-6500 3825);
DISPLAY 0.617021 (-6500 3825);
PAINT SKYBLUE (-6500 3825);
FORCEPROP 1 LAST MATERIAL X6S
J 0
(-6500 3925);
DISPLAY 0.617021 (-6500 3925);
PAINT SKYBLUE (-6500 3925);
FORCEPROP 1 LASTPIN (-6550 3925) $PN 2
J 0
(-6540 3905);
DISPLAY 0.617021 (-6540 3905);
PAINT ORANGE (-6540 3905);
FORCEPROP 1 LASTPIN (-6550 4125) $PN 1
J 0
(-6540 4105);
DISPLAY 0.617021 (-6540 4105);
PAINT ORANGE (-6540 4105);
FORCEPROP 1 LAST LOCATION C9N25
J 0
(-6500 4125);
DISPLAY 0.617021 (-6500 4125);
PAINT AQUA (-6500 4125);
FORCEPROP 1 LAST TOLERANCE 10%
J 0
(-6500 3975);
DISPLAY 0.617021 (-6500 3975);
PAINT SKYBLUE (-6500 3975);
FORCEPROP 1 LAST VALUE 10UF
J 0
(-6500 4075);
DISPLAY 0.617021 (-6500 4075);
PAINT SKYBLUE (-6500 4075);
FORCEPROP 1 LAST VOLTAGE 16V
J 0
(-6500 4025);
DISPLAY 0.617021 (-6500 4025);
PAINT SKYBLUE (-6500 4025);
FORCEPROP 2 LAST CDS_LIB mstr_discrete
J 0
(-6550 4025);
PAINT ORANGE (-6550 4025);
DISPLAY INVISIBLE (-6550 4025);
FORCEPROP 2 LAST ROOM PVCCIN_CPU1_PWR_VR
J 0
(-6500 4175);
DISPLAY 1.361702 (-6500 4175);
PAINT ORANGE (-6500 4175);
DISPLAY INVISIBLE (-6500 4175);
FORCEPROP 1 LAST PATH I8
J 0
(-6500 4175);
DISPLAY 0.978723 (-6500 4175);
PAINT WHITE (-6500 4175);
DISPLAY INVISIBLE (-6500 4175);
FORCEPROP 2 LAST SEC 1
J 0
(-6500 4225);
DISPLAY 0.680851 (-6500 4225);
PAINT MONO (-6500 4225);
DISPLAY INVISIBLE (-6500 4225);
FORCEPROP 2 LAST SEC_TYPE 0805
J 0
(-6500 4225);
DISPLAY 1.021277 (-6500 4225);
PAINT ORANGE (-6500 4225);
DISPLAY INVISIBLE (-6500 4225);
FORCEADD IND-120NH-30-GP..1
R 1
(-1400 3500);
FORCEPROP 1 LAST VALUE IND-120NH-30-GP
J 0
(-1550 3400);
DISPLAY 0.617021 (-1550 3400);
PAINT GREEN (-1550 3400);
FORCEPROP 1 LAST LOCATION L1C2
J 0
(-1550 3550);
DISPLAY 0.617021 (-1550 3550);
PAINT GREEN (-1550 3550);
FORCEPROP 2 LASTPIN (-1550 3475) $PN 1
J 2
(-1560 3485);
DISPLAY 0.808511 (-1560 3485);
PAINT ORANGE (-1560 3485);
FORCEPROP 2 LAST ATTRIBUTE 120NH
J 0
(-1550 3350);
DISPLAY 0.638298 (-1550 3350);
PAINT GREEN (-1550 3350);
FORCEPROP 2 LAST RATED ISAT=94A@25C
J 0
(-1550 3300);
DISPLAY 0.638298 (-1550 3300);
PAINT GREEN (-1550 3300);
FORCEPROP 2 LASTPIN (-1250 3475) $PN 2
J 0
(-1240 3485);
DISPLAY 0.808511 (-1240 3485);
PAINT ORANGE (-1240 3485);
FORCEPROP 2 LAST PACK_SIZE DCR=0.17MOHM
J 0
(-1550 3200);
DISPLAY 0.638298 (-1550 3200);
PAINT GREEN (-1550 3200);
FORCEPROP 2 LAST TYPE IRMS=66A@DELTA_T<40C
J 0
(-1550 3250);
DISPLAY 0.638298 (-1550 3250);
PAINT GREEN (-1550 3250);
FORCEPROP 1 LAST PATH I80
R 1
J 0
(-1400 3500);
DISPLAY 0.617021 (-1400 3500);
PAINT GREEN (-1400 3500);
DISPLAY INVISIBLE (-1400 3500);
FORCEPROP 1 LAST PART_NUMBER 068.1202N.M001
R 1
J 0
(-1400 3500);
DISPLAY 0.617021 (-1400 3500);
PAINT GREEN (-1400 3500);
DISPLAY INVISIBLE (-1400 3500);
FORCEPROP 2 LAST CDS_LIB w_hdl
R 1
J 0
(-1400 3500);
PAINT MONO (-1400 3500);
DISPLAY INVISIBLE (-1400 3500);
FORCEPROP 1 LAST CDS_LMAN_SYM_OUTLINE -75,100,75,-100
R 1
J 0
(-1400 3500);
DISPLAY 0.468085 (-1400 3500);
PAINT GREEN (-1400 3500);
DISPLAY INVISIBLE (-1400 3500);
FORCEPROP 2 LAST SEC_TYPE DISCRET-GB2
J 0
(-1525 3575);
DISPLAY 1.021277 (-1525 3575);
PAINT ORANGE (-1525 3575);
DISPLAY INVISIBLE (-1525 3575);
FORCEPROP 2 LAST SEC 1
J 0
(-1525 3575);
DISPLAY 0.680851 (-1525 3575);
PAINT MONO (-1525 3575);
DISPLAY INVISIBLE (-1525 3575);
FORCEPROP 1 LAST PACK_TYPE DISCRET-GB2
R 1
J 0
(-1400 3500);
DISPLAY 0.617021 (-1400 3500);
PAINT GREEN (-1400 3500);
DISPLAY INVISIBLE (-1400 3500);
FORCEADD IND-80NH-1-GP..1
R 1
(-3050 2275);
FORCEPROP 1 LAST VALUE IND-80NH-1-GP
J 0
(-3215 2200);
DISPLAY 0.617021 (-3215 2200);
PAINT GREEN (-3215 2200);
FORCEPROP 1 LAST LOCATION L1B2
J 0
(-3190 2325);
DISPLAY 0.617021 (-3190 2325);
PAINT GREEN (-3190 2325);
FORCEPROP 2 LASTPIN (-3200 2250) $PN 1
J 2
(-3210 2260);
DISPLAY 0.808511 (-3210 2260);
PAINT ORANGE (-3210 2260);
FORCEPROP 2 LASTPIN (-2900 2250) $PN 2
J 0
(-2890 2260);
DISPLAY 0.808511 (-2890 2260);
PAINT ORANGE (-2890 2260);
FORCEPROP 2 LAST ATTRIBUTE 80NH
J 0
(-3225 2150);
DISPLAY 0.638298 (-3225 2150);
PAINT GREEN (-3225 2150);
FORCEPROP 2 LAST RATED ISAT=50A@25C
J 0
(-3225 2100);
DISPLAY 0.638298 (-3225 2100);
PAINT GREEN (-3225 2100);
FORCEPROP 2 LAST PACK_SIZE DCR=0.22MOHM
J 0
(-3225 2000);
DISPLAY 0.638298 (-3225 2000);
PAINT GREEN (-3225 2000);
FORCEPROP 2 LAST TYPE IRMS=34A@DELTA_T<45C
J 0
(-3225 2050);
DISPLAY 0.638298 (-3225 2050);
PAINT GREEN (-3225 2050);
FORCEPROP 1 LAST PATH I81
R 1
J 0
(-3050 2275);
DISPLAY 0.617021 (-3050 2275);
PAINT GREEN (-3050 2275);
DISPLAY INVISIBLE (-3050 2275);
FORCEPROP 1 LAST PACK_TYPE DISCRET-GC2
R 1
J 0
(-3050 2275);
DISPLAY 0.617021 (-3050 2275);
PAINT GREEN (-3050 2275);
DISPLAY INVISIBLE (-3050 2275);
FORCEPROP 2 LAST SEC 1
J 0
(-3200 2250);
DISPLAY 0.680851 (-3200 2250);
PAINT MONO (-3200 2250);
DISPLAY INVISIBLE (-3200 2250);
FORCEPROP 2 LAST SEC_TYPE DISCRET-GC2
J 0
(-3200 2250);
DISPLAY 1.021277 (-3200 2250);
PAINT ORANGE (-3200 2250);
DISPLAY INVISIBLE (-3200 2250);
FORCEPROP 1 LAST CDS_LMAN_SYM_OUTLINE -75,100,75,-100
R 1
J 0
(-3050 2275);
DISPLAY 0.468085 (-3050 2275);
PAINT GREEN (-3050 2275);
DISPLAY INVISIBLE (-3050 2275);
FORCEPROP 2 LAST CDS_LIB w_hdl
R 1
J 0
(-3050 2275);
PAINT MONO (-3050 2275);
DISPLAY INVISIBLE (-3050 2275);
FORCEPROP 1 LAST PART_NUMBER 068.8001N.M001
R 1
J 0
(-3050 2275);
DISPLAY 0.617021 (-3050 2275);
PAINT GREEN (-3050 2275);
DISPLAY INVISIBLE (-3050 2275);
FORCEADD SC1U10V2KX-4-GP..1
(-5125 4025);
FORCEPROP 1 LAST LOCATION C1C18
J 0
(-5000 4105);
DISPLAY 0.617021 (-5000 4105);
PAINT GREEN (-5000 4105);
FORCEPROP 2 LAST RATED 10V
J 0
(-5000 3950);
DISPLAY 0.638298 (-5000 3950);
PAINT GREEN (-5000 3950);
FORCEPROP 2 LAST TOLERANCE 10%
J 0
(-5000 4000);
DISPLAY 0.638298 (-5000 4000);
PAINT GREEN (-5000 4000);
FORCEPROP 2 LAST ATTRIBUTE 1UF
J 0
(-5000 4050);
DISPLAY 0.638298 (-5000 4050);
PAINT GREEN (-5000 4050);
FORCEPROP 2 LASTPIN (-5125 3950) $PN 2
R 1
J 2
(-5135 3940);
DISPLAY 0.808511 (-5135 3940);
PAINT ORANGE (-5135 3940);
FORCEPROP 2 LASTPIN (-5125 4100) $PN 1
R 1
J 0
(-5135 4110);
DISPLAY 0.808511 (-5135 4110);
PAINT ORANGE (-5135 4110);
FORCEPROP 1 LAST VALUE SC1U10V2KX-4-GP
R 1
J 0
(-5025 3825);
DISPLAY 0.617021 (-5025 3825);
PAINT GREEN (-5025 3825);
FORCEPROP 2 LAST PACK_SIZE 0402
J 0
(-5000 3900);
DISPLAY 0.638298 (-5000 3900);
PAINT GREEN (-5000 3900);
FORCEPROP 1 LAST PACK_TYPE SMD-BCG6
J 0
(-5125 4025);
DISPLAY 0.617021 (-5125 4025);
PAINT GREEN (-5125 4025);
DISPLAY INVISIBLE (-5125 4025);
FORCEPROP 2 LAST SEC 1
J 0
(-5100 4100);
DISPLAY 0.680851 (-5100 4100);
PAINT MONO (-5100 4100);
DISPLAY INVISIBLE (-5100 4100);
FORCEPROP 2 LAST SEC_TYPE SMD-BCG6
J 0
(-5100 4100);
DISPLAY 1.021277 (-5100 4100);
PAINT ORANGE (-5100 4100);
DISPLAY INVISIBLE (-5100 4100);
FORCEPROP 1 LAST CDS_LMAN_SYM_OUTLINE -50,25,50,-25
J 0
(-5125 4025);
DISPLAY 0.468085 (-5125 4025);
PAINT GREEN (-5125 4025);
DISPLAY INVISIBLE (-5125 4025);
FORCEPROP 1 LAST PATH I89
J 0
(-5125 4025);
DISPLAY 0.617021 (-5125 4025);
PAINT GREEN (-5125 4025);
DISPLAY INVISIBLE (-5125 4025);
FORCEPROP 2 LAST CDS_LIB w_hdl
J 0
(-5125 4025);
PAINT MONO (-5125 4025);
DISPLAY INVISIBLE (-5125 4025);
FORCEPROP 1 LAST PART_NUMBER 78.10523.8FL
J 0
(-5125 4025);
DISPLAY 0.617021 (-5125 4025);
PAINT GREEN (-5125 4025);
DISPLAY INVISIBLE (-5125 4025);
FORCEADD RES..1
(-5475 1050);
FORCEPROP 1 LAST PART_NUMBER G21796-017
J 0
(-5525 1150);
DISPLAY 0.617021 (-5525 1150);
PAINT BLUE (-5525 1150);
FORCEPROP 1 LASTPIN (-5375 1050) $PN 2
J 0
(-5413 1062);
DISPLAY 0.617021 (-5413 1062);
PAINT GREEN (-5413 1062);
FORCEPROP 1 LAST LOCATION R1E8
J 0
(-5525 1100);
DISPLAY 0.617021 (-5525 1100);
PAINT AQUA (-5525 1100);
FORCEPROP 1 LASTPIN (-5575 1050) $PN 1
J 0
(-5563 1062);
DISPLAY 0.617021 (-5563 1062);
PAINT GREEN (-5563 1062);
FORCEPROP 1 LAST VALUE 100.0
J 2
(-5475 975);
DISPLAY 0.617021 (-5475 975);
PAINT SKYBLUE (-5475 975);
FORCEPROP 1 LAST TOLERANCE 1%
J 0
(-5425 975);
DISPLAY 0.617021 (-5425 975);
PAINT SKYBLUE (-5425 975);
FORCEPROP 1 LAST PACK_TYPE 0402
J 0
(-5550 875);
DISPLAY 0.617021 (-5550 875);
PAINT SKYBLUE (-5550 875);
FORCEPROP 1 LAST WATTAGE 1/16W
J 2
(-5475 925);
DISPLAY 0.617021 (-5475 925);
PAINT SKYBLUE (-5475 925);
FORCEPROP 2 LAST CDS_SEC 1
J 0
(-5525 1250);
PAINT MONO (-5525 1250);
DISPLAY INVISIBLE (-5525 1250);
FORCEPROP 2 LAST $SEC 1
J 0
(-5525 1250);
PAINT MONO (-5525 1250);
DISPLAY INVISIBLE (-5525 1250);
FORCEPROP 2 LAST CDS_LIB mstr_discrete
J 0
(-5475 1050);
PAINT ORANGE (-5475 1050);
DISPLAY INVISIBLE (-5475 1050);
FORCEPROP 1 LAST PATH I9
J 0
(-5525 1200);
DISPLAY 0.978723 (-5525 1200);
PAINT WHITE (-5525 1200);
DISPLAY INVISIBLE (-5525 1200);
FORCEPROP 2 LAST CDS_LOCATION R1E8
J 0
(-5525 1100);
DISPLAY 0.617021 (-5525 1100);
PAINT AQUA (-5525 1100);
DISPLAY INVISIBLE (-5525 1100);
FORCEPROP 2 LAST BOM_COST PROC_VRD_VCCIN_CPU0
J 0
(-5525 1200);
PAINT MONO (-5525 1200);
DISPLAY INVISIBLE (-5525 1200);
FORCEPROP 2 LAST ROOM PVCCIN_CPU1_VSENSE_VR
J 0
(-5525 1150);
PAINT ORANGE (-5525 1150);
DISPLAY INVISIBLE (-5525 1150);
FORCEPROP 1 LAST MATERIAL CHIP
J 0
(-5450 925);
PAINT SKYBLUE (-5450 925);
DISPLAY INVISIBLE (-5450 925);
FORCEADD 1R3F-GP..1
(-2400 2975);
FORCEPROP 2 LAST PACK_SIZE 0603
J 0
(-2350 2850);
DISPLAY 0.638298 (-2350 2850);
PAINT GREEN (-2350 2850);
FORCEPROP 2 LAST RATED 1/10W
J 0
(-2350 2900);
DISPLAY 0.638298 (-2350 2900);
PAINT GREEN (-2350 2900);
FORCEPROP 1 LAST LOCATION RT10
J 0
(-2350 3100);
DISPLAY 0.617021 (-2350 3100);
PAINT GREEN (-2350 3100);
FORCEPROP 1 LAST VALUE 1R3F-GP
J 0
(-2350 3050);
DISPLAY 0.617021 (-2350 3050);
PAINT GREEN (-2350 3050);
FORCEPROP 2 LAST ATTRIBUTE 1 OHM
J 0
(-2350 3000);
DISPLAY 0.638298 (-2350 3000);
PAINT GREEN (-2350 3000);
FORCEPROP 0 LAST POP NOPOP
J 0
(-2350 2800);
DISPLAY 0.638298 (-2350 2800);
PAINT RED (-2350 2800);
FORCEPROP 2 LASTPIN (-2400 2850) $PN 2
R 1
J 2
(-2410 2840);
DISPLAY 0.808511 (-2410 2840);
PAINT ORANGE (-2410 2840);
FORCEPROP 2 LASTPIN (-2400 3100) $PN 1
R 1
J 0
(-2410 3110);
DISPLAY 0.808511 (-2410 3110);
PAINT ORANGE (-2410 3110);
FORCEPROP 2 LAST TOLERANCE 1%
J 0
(-2350 2950);
DISPLAY 0.638298 (-2350 2950);
PAINT GREEN (-2350 2950);
FORCEPROP 1 LAST PACK_TYPE RCL_GP
J 0
(-2400 2975);
DISPLAY 0.617021 (-2400 2975);
PAINT GREEN (-2400 2975);
DISPLAY INVISIBLE (-2400 2975);
FORCEPROP 2 LAST SEC 1
J 0
(-2350 3075);
DISPLAY 0.680851 (-2350 3075);
PAINT MONO (-2350 3075);
DISPLAY INVISIBLE (-2350 3075);
FORCEPROP 2 LAST SEC_TYPE RCL_GP
J 0
(-2350 3075);
DISPLAY 1.021277 (-2350 3075);
PAINT ORANGE (-2350 3075);
DISPLAY INVISIBLE (-2350 3075);
FORCEPROP 1 LAST PART_NUMBER 64.1R005.55L
J 0
(-2400 2975);
DISPLAY 0.617021 (-2400 2975);
PAINT GREEN (-2400 2975);
DISPLAY INVISIBLE (-2400 2975);
FORCEPROP 2 LAST CDS_LIB w_hdl
J 0
(-2400 2975);
DISPLAY INVISIBLE (-2400 2975);
FORCEPROP 1 LAST CDS_LMAN_SYM_OUTLINE -50,75,50,-75
J 0
(-2400 2975);
DISPLAY 0.468085 (-2400 2975);
PAINT GREEN (-2400 2975);
DISPLAY INVISIBLE (-2400 2975);
FORCEPROP 1 LAST PATH I90
J 0
(-2400 2975);
DISPLAY 0.617021 (-2400 2975);
PAINT GREEN (-2400 2975);
DISPLAY INVISIBLE (-2400 2975);
FORCEADD DNS..2
(-6295 1695);
PAINT RED (-6295 1695);
FORCEPROP 2 LAST CDS_LIB mstr_misc
J 0
(-6295 1695);
PAINT ORANGE (-6295 1695);
DISPLAY INVISIBLE (-6295 1695);
FORCEPROP 1 LAST COMMENT_BODY TRUE
R 1
J 0
(-6220 1470);
DISPLAY 0.872340 (-6220 1470);
PAINT GREEN (-6220 1470);
DISPLAY INVISIBLE (-6220 1470);
FORCEADD INTEL_CORP_BPAGE..1
(0 0);
FORCEPROP 1 LAST CDS_CON_LAST_MODIFIED Fri Jun 16 17:49:16 2017
J 0
(-1425 325);
PAINT ORANGE (-1425 325);
DISPLAY INVISIBLE (-1425 325);
FORCEPROP 1 LAST CUSTOM_TXT_CDS <CURRENT_DESIGN_SHEET> OF <TOTAL_DESIGN_SHEETS>
J 0
(-500 25);
PAINT ORANGE (-500 25);
FORCEPROP 1 LAST CUSTOM_TXT_CDS <CON_LAST_MODIFIED>
J 0
(-4000 100);
PAINT ORANGE (-4000 100);
FORCEPROP 2 LAST CUSTOM_TXT_CDS <XR_PAGE_TITLE>
J 0
(-7890 5250);
DISPLAY 0.638298 (-7890 5250);
PAINT PINK (-7890 5250);
DISPLAY INVISIBLE (-7890 5250);
FORCEPROP 1 LAST SCH_TITLE VCCIN CPU1 (4 OF 4)
J 0
(-7950 50);
DISPLAY 1.212766 (-7950 50);
PAINT ORANGE (-7950 50);
FORCEPROP 2 LAST CDS_LIB mstr_symbols
J 0
(0 0);
PAINT ORANGE (0 0);
DISPLAY INVISIBLE (0 0);
FORCEPROP 2 LAST PAGE_BORDER TRUE
J 0
(-7890 5250);
DISPLAY 0.638298 (-7890 5250);
PAINT PINK (-7890 5250);
DISPLAY INVISIBLE (-7890 5250);
FORCEPROP 1 LAST COMMENT_BODY TRUE
J 0
(12 12);
DISPLAY 0.468085 (12 12);
PAINT GREEN (12 12);
DISPLAY INVISIBLE (12 12);
FORCEPROP 2 LAST CDS_XR_PAGE_TITLE CR-209 : @BASEBOARD_FAB2_LIB.BASEBOARD_FAB2(SCH_1):PAGE209
J 0
(-7890 5250);
DISPLAY 0.638298 (-7890 5250);
PAINT PINK (-7890 5250);
DISPLAY INVISIBLE (-7890 5250);
FORCEADD DNS..2
(-995 3920);
PAINT RED (-995 3920);
FORCEPROP 2 LAST CDS_LIB mstr_misc
J 0
(-995 3920);
PAINT ORANGE (-995 3920);
DISPLAY INVISIBLE (-995 3920);
FORCEPROP 1 LAST COMMENT_BODY TRUE
R 1
J 0
(-920 3695);
DISPLAY 0.872340 (-920 3695);
PAINT GREEN (-920 3695);
DISPLAY INVISIBLE (-920 3695);
FORCEADD DESIGN_NOTE..1
(-7625 2800);
PAINT PURPLE (-7625 2800);
FORCEPROP 2 LAST BOM_COST SM_CONTROLLER
J 0
(-7825 2750);
PAINT MONO (-7825 2750);
DISPLAY INVISIBLE (-7825 2750);
FORCEPROP 2 LAST ROOM PVCCIN_CPU0_VR
J 0
(-7825 2750);
PAINT MONO (-7825 2750);
DISPLAY INVISIBLE (-7825 2750);
FORCEPROP 2 LAST CDS_LIB mstr_symbols
J 0
(-7625 2800);
PAINT ORANGE (-7625 2800);
DISPLAY INVISIBLE (-7625 2800);
FORCEPROP 1 LAST COMMENT_BODY TRUE
J 0
(-7600 2900);
DISPLAY 1.319149 (-7600 2900);
PAINT GREEN (-7600 2900);
DISPLAY INVISIBLE (-7600 2900);
WIRE 16 -1 (-4825 825)(-4825 1050);
WIRE 16 -1 (-4825 1050)(-5375 1050);
WIRE 16 -1 (-4650 2300)(-4650 2400);
WIRE 16 -1 (-5400 2300)(-4650 2300);
WIRE 16 -1 (-6350 4400)(-6350 4275);
WIRE 16 -1 (-6350 4275)(-6225 4275);
WIRE 16 -1 (-6350 4275)(-6550 4275);
WIRE 16 -1 (-6850 4275)(-6550 4275);
WIRE 16 -1 (-6550 4125)(-6550 4275);
WIRE 16 -1 (-6225 4275)(-5925 4275);
WIRE 16 -1 (-6225 4125)(-6225 4275);
WIRE 16 -1 (-3875 4275)(-5925 4275);
WIRE 16 -1 (-5925 4125)(-5925 4275);
WIRE 16 -1 (-7125 4275)(-6850 4275);
WIRE 16 -1 (-6850 4125)(-6850 4275);
WIRE 16 -1 (-7125 4125)(-7125 4275);
WIRE 16 -1 (-3875 4225)(-3875 4275);
WIRE 16 -1 (-3875 4275)(-3750 4275);
WIRE 16 -1 (-3750 4225)(-3875 4225);
WIRE 16 -1 (-2675 3175)(-2675 3225);
WIRE 16 -1 (-2675 3225)(-2675 3275);
WIRE 16 -1 (-2675 3225)(-2750 3225);
WIRE 16 -1 (-2675 3275)(-2675 3325);
WIRE 16 -1 (-2675 3275)(-2750 3275);
WIRE 16 -1 (-2675 3325)(-2675 3375);
WIRE 16 -1 (-2675 3325)(-2750 3325);
WIRE 16 -1 (-2750 3375)(-2675 3375);
WIRE 16 -1 (-1200 1700)(-1200 1775);
WIRE 16 -1 (-950 1775)(-1200 1775);
WIRE 16 -1 (-1200 1775)(-1425 1775);
WIRE 16 -1 (-1425 1975)(-1425 1775);
WIRE 16 -1 (-600 1775)(-950 1775);
WIRE 16 -1 (-950 1950)(-950 1775);
WIRE 16 -1 (-600 1950)(-600 1775);
WIRE 16 -1 (-6850 3575)(-6850 3750);
WIRE 16 -1 (-6850 3750)(-6550 3750);
WIRE 16 -1 (-6850 3750)(-7125 3750);
WIRE 16 -1 (-6850 3925)(-6850 3750);
WIRE 16 -1 (-7125 3925)(-7125 3750);
WIRE 16 -1 (-6225 3750)(-6550 3750);
WIRE 16 -1 (-6550 3925)(-6550 3750);
WIRE 16 -1 (-6225 3750)(-5925 3750);
WIRE 16 -1 (-6225 3925)(-6225 3750);
WIRE 16 -1 (-5625 3750)(-5925 3750);
WIRE 16 -1 (-5925 3925)(-5925 3750);
WIRE 16 -1 (-5625 3750)(-5125 3750);
WIRE 16 -1 (-5625 3925)(-5625 3750);
WIRE 16 -1 (-4800 3750)(-5125 3750);
WIRE 16 -1 (-5125 3950)(-5125 3750);
WIRE 16 -1 (-4800 3925)(-4800 3750);
WIRE 16 -1 (-350 2975)(-350 3000);
WIRE 16 -1 (-750 3000)(-350 3000);
WIRE 16 -1 (-350 3150)(-350 3000);
WIRE 16 -1 (-750 3000)(-750 3150);
WIRE 16 -1 (-350 3475)(-350 3525);
WIRE 16 -1 (-750 3475)(-350 3475);
WIRE 16 -1 (-350 3350)(-350 3475);
WIRE 16 -1 (-1075 3475)(-750 3475);
WIRE 16 -1 (-750 3350)(-750 3475);
WIRE 16 -1 (-1075 2775)(-1075 3475);
WIRE 16 -1 (-1250 3475)(-1075 3475);
WIRE 16 -1 (-3825 2775)(-1075 2775);
WIRE 16 -1 (-3825 3925)(-3825 2775);
WIRE 16 -1 (-3750 3925)(-3825 3925);
WIRE 16 -1 (-600 2475)(-600 2250);
WIRE 16 -1 (-600 2250)(-950 2250);
WIRE 16 -1 (-600 2150)(-600 2250);
WIRE 16 -1 (-1425 2250)(-950 2250);
WIRE 16 -1 (-950 2150)(-950 2250);
WIRE 16 -1 (-1425 2175)(-1425 2250);
WIRE 16 -1 (-1425 2250)(-2900 2250);
WIRE 16 -1 (-3350 2425)(-3350 2250);
WIRE 16 -1 (-3200 2250)(-3350 2250);
WIRE 16 -1 (-4550 4650)(-4550 4700);
WIRE 16 -1 (-4025 4650)(-4550 4650);
WIRE 16 -1 (-4550 4650)(-4800 4650);
WIRE 16 -1 (-4800 4650)(-5125 4650);
WIRE 16 -1 (-4800 4125)(-4800 4650);
WIRE 16 -1 (-4025 4650)(-4025 4125);
WIRE 16 -1 (-4025 4125)(-4025 4025);
WIRE 16 -1 (-4025 4125)(-3750 4125);
WIRE 16 -1 (-5325 4650)(-5125 4650);
WIRE 16 -1 (-5125 4100)(-5125 4650);
WIRE 16 -1 (-4025 4025)(-3750 4025);
WIRE 16 -1 (-1000 3800)(-1000 3825);
WIRE 16 -1 (-3950 3175)(-3950 3075);
WIRE 16 -1 (-1950 3725)(-1950 3625);
WIRE 16 -1 (-1950 3925)(-1950 3975);
WIRE 16 -1 (-1950 3975)(-1750 3975);
WIRE 16 -1 (-2750 3975)(-2750 3825);
WIRE 16 -1 (-2750 3975)(-1950 3975);
FORCEPROP 2 LAST SIG_NAME A_TSENSE_PVCCIN_CPU1
J 0
(-2718 3995);
DISPLAY 0.617021 (-2718 3995);
PAINT ORANGE (-2718 3995);
WIRE 16 2175 (-5225 3825)(-4525 3825);
WIRE 16 2175 (-4525 4225)(-4525 3825);
WIRE 16 2175 (-5225 4225)(-5225 3825);
WIRE 16 2175 (-5225 4225)(-4525 4225);
WIRE 16 682 (-7850 2125)(-7850 2875);
WIRE 16 682 (-7150 2125)(-7850 2125);
WIRE 16 682 (-7850 2875)(-7150 2875);
WIRE 16 682 (-7150 2875)(-7150 2125);
WIRE 16 -1 (-5625 4650)(-5525 4650);
WIRE 16 -1 (-5625 4125)(-5625 4325);
WIRE 16 -1 (-5625 4325)(-5625 4650);
WIRE 16 -1 (-5625 4325)(-3750 4325);
FORCEPROP 0 LAST VOLTAGE 5
J 0
(-4350 4400);
DISPLAY 1.021277 (-4350 4400);
PAINT SKYBLUE (-4350 4400);
DISPLAY INVISIBLE (-4350 4400);
FORCEPROP 2 LAST SIG_NAME VR_PVCCIN_CPU1_PH5_VCIN
J 0
(-5615 4335);
DISPLAY 0.617021 (-5615 4335);
PAINT ORANGE (-5615 4335);
FORCEPROP 2 LASTPROP $XRERR UNIQUE?
J 0
(-5855 4335);
DISPLAY 0.638298 (-5855 4335);
PAINT MONO (-5855 4335);
DISPLAY INVISIBLE (-5855 4335);
WIRE 3 682 (-5175 3900)(-5075 3900);
WIRE 3 682 (-5175 4150)(-5175 3900);
WIRE 3 682 (-5075 3900)(-5075 4150);
WIRE 3 682 (-5075 4150)(-5175 4150);
WIRE 3 2175 (-5575 4400)(-5225 4400);
WIRE 3 2175 (-5225 4700)(-5225 4400);
WIRE 3 2175 (-5575 4700)(-5575 4400);
WIRE 3 2175 (-5575 4700)(-5225 4700);
WIRE 3 682 (-2150 2500)(-1550 2500);
WIRE 3 682 (-2150 2500)(-2150 1850);
WIRE 3 682 (-1550 850)(-1550 2500);
WIRE 3 682 (-3450 850)(-1550 850);
WIRE 3 682 (-2150 1850)(-3450 1850);
WIRE 3 682 (-3450 1850)(-3450 850);
WIRE 3 2175 (-2575 2725)(-1825 2725);
WIRE 3 2175 (-1825 3450)(-1825 2725);
WIRE 3 2175 (-2575 3450)(-2575 2725);
WIRE 3 2175 (-2575 3450)(-1825 3450);
WIRE 16 -1 (-2400 3200)(-2400 3150);
WIRE 16 -1 (-2400 3150)(-2400 3100);
WIRE 16 -1 (-2400 3150)(-1850 3150);
FORCEPROP 2 LAST SIG_NAME VR_PVCCIN_CPU1_PHASE5_RC
J 0
(-2340 3160);
DISPLAY 0.617021 (-2340 3160);
PAINT ORANGE (-2340 3160);
FORCEPROP 2 LASTPROP $XRERR UNIQUE?
J 0
(-1820 3150);
DISPLAY 0.638298 (-1820 3150);
PAINT MONO (-1820 3150);
DISPLAY INVISIBLE (-1820 3150);
WIRE 3 2175 (-2200 3550)(-1625 3550);
WIRE 3 2175 (-1625 4025)(-1625 3550);
WIRE 3 2175 (-2200 4025)(-2200 3550);
WIRE 3 2175 (-2200 4025)(-1625 4025);
WIRE 16 -1 (-4050 3475)(-3750 3475);
WIRE 16 -1 (-4050 3475)(-4050 3575);
WIRE 16 -1 (-4700 3575)(-4050 3575);
FORCEPROP 2 LAST SIG_NAME VR_PVCCIN_CPU1_PH5_BOOT_R
J 0
(-4529 3572);
DISPLAY 0.617021 (-4529 3572);
PAINT ORANGE (-4529 3572);
FORCEPROP 2 LASTPROP $XRERR UNIQUE?
J 0
(-4769 3572);
DISPLAY 0.638298 (-4769 3572);
PAINT MONO (-4769 3572);
DISPLAY INVISIBLE (-4769 3572);
WIRE 3 2175 (-5000 3400)(-4550 3400);
WIRE 3 2175 (-4550 3650)(-4550 3400);
WIRE 3 2175 (-5000 3650)(-5000 3400);
WIRE 3 2175 (-5000 3650)(-4550 3650);
WIRE 16 -1 (-3750 3775)(-4475 3775);
FORCEPROP 0 LAST SIG_NAME TP_PVCCIN_CPU1_PH5_GL_0
J 0
(-4448 3790);
DISPLAY 0.617021 (-4448 3790);
PAINT ORANGE (-4448 3790);
FORCEPROP 2 LASTPROP $XRERR UNIQUE?
J 0
(-4715 3775);
DISPLAY 0.638298 (-4715 3775);
PAINT MONO (-4715 3775);
DISPLAY INVISIBLE (-4715 3775);
WIRE 16 -1 (-4050 3425)(-3750 3425);
WIRE 16 -1 (-4050 3350)(-4050 3425);
WIRE 16 -1 (-5900 3350)(-4050 3350);
FORCEPROP 0 LAST VOLTAGE 5
J 0
(-5800 3425);
DISPLAY 1.021277 (-5800 3425);
PAINT SKYBLUE (-5800 3425);
DISPLAY INVISIBLE (-5800 3425);
FORCEPROP 2 LAST SIG_NAME VR_PVCCIN_CPU1_PH5_PHASE
J 0
(-5815 3360);
DISPLAY 0.617021 (-5815 3360);
PAINT ORANGE (-5815 3360);
FORCEPROP 2 LASTPROP $XRERR UNIQUE?
J 0
(-6055 3360);
DISPLAY 0.638298 (-6055 3360);
PAINT MONO (-6055 3360);
DISPLAY INVISIBLE (-6055 3360);
WIRE 16 2175 (-6225 3150)(-5150 3150);
WIRE 16 2175 (-5150 3625)(-5150 3150);
WIRE 16 2175 (-6225 3625)(-6225 3150);
WIRE 16 2175 (-6225 3625)(-5150 3625);
WIRE 16 -1 (-3750 3825)(-4475 3825);
FORCEPROP 0 LAST SIG_NAME TP_PVCCIN_CPU1_PH5_GL_1
J 0
(-4448 3840);
DISPLAY 0.617021 (-4448 3840);
PAINT ORANGE (-4448 3840);
FORCEPROP 2 LASTPROP $XRERR UNIQUE?
J 0
(-4715 3825);
DISPLAY 0.638298 (-4715 3825);
PAINT MONO (-4715 3825);
DISPLAY INVISIBLE (-4715 3825);
WIRE 16 273 (-6925 1975)(-6925 1400);
WIRE 16 273 (-6425 1975)(-6925 1975);
WIRE 16 273 (-6925 1400)(-6425 1400);
WIRE 16 273 (-6425 1400)(-6425 1975);
WIRE 16 -1 (-5925 1050)(-5575 1050);
WIRE 16 -1 (-5925 1050)(-5925 1450);
WIRE 16 -1 (-5925 1450)(-5575 1450);
WIRE 16 -1 (-6300 1600)(-6300 1450);
WIRE 16 -1 (-6300 1450)(-5925 1450);
WIRE 16 -1 (-6525 1450)(-6300 1450);
WIRE 16 -1 (-6525 1675)(-6525 1450);
WIRE 16 -1 (-6850 1675)(-6525 1675);
WIRE 16 -1 (-6850 1575)(-6850 1675);
WIRE 16 -1 (-7575 1575)(-6850 1575);
FORCEPROP 2 LAST SIG_NAME VSENSE_PVCCIN_CPU1_N
J 0
(-7585 1585);
DISPLAY 0.617021 (-7585 1585);
PAINT ORANGE (-7585 1585);
WIRE 16 -1 (-5375 1450)(-4350 1450);
FORCEPROP 2 LAST SIG_NAME VSENSE_PVCCIN_CPU1_SKT_VRTN
J 0
(-5160 1460);
DISPLAY 0.617021 (-5160 1460);
PAINT ORANGE (-5160 1460);
WIRE 3 682 (-2700 4075)(-2600 4075);
WIRE 16 -1 (-5400 1900)(-4350 1900);
FORCEPROP 2 LAST SIG_NAME VSENSE_PVCCIN_CPU1_SKT_VSEN
J 0
(-5223 1919);
DISPLAY 0.617021 (-5223 1919);
PAINT ORANGE (-5223 1919);
WIRE 16 -1 (-5925 2300)(-5600 2300);
WIRE 16 -1 (-5925 1900)(-5600 1900);
WIRE 16 -1 (-5925 1900)(-5925 2300);
WIRE 16 -1 (-6300 1800)(-6300 1900);
WIRE 16 -1 (-6300 1900)(-5925 1900);
WIRE 16 -1 (-6525 1900)(-6300 1900);
WIRE 16 -1 (-6525 1750)(-6525 1900);
WIRE 16 -1 (-6850 1750)(-6525 1750);
WIRE 16 -1 (-6850 1750)(-6850 1850);
WIRE 16 -1 (-7575 1850)(-6850 1850);
FORCEPROP 2 LAST SIG_NAME VSENSE_PVCCIN_CPU1_P
J 0
(-7585 1860);
DISPLAY 0.617021 (-7585 1860);
PAINT ORANGE (-7585 1860);
WIRE 16 -1 (-3950 4800)(-1175 4800);
FORCEPROP 2 LAST SIG_NAME VR_PVCCIN_CPU1_AIREF5
J 2
(-1215 4809);
DISPLAY 0.617021 (-1215 4809);
PAINT ORANGE (-1215 4809);
WIRE 16 -1 (-3950 3375)(-3950 3575);
WIRE 16 -1 (-3750 3575)(-3950 3575);
WIRE 16 -1 (-3950 3575)(-3950 4800);
WIRE 16 -1 (-2400 3475)(-2750 3475);
FORCEPROP 0 LAST VOLTAGE 5
J 0
(-2500 3550);
DISPLAY 1.021277 (-2500 3550);
PAINT SKYBLUE (-2500 3550);
DISPLAY INVISIBLE (-2500 3550);
FORCEPROP 2 LAST SIG_NAME VR_PVCCIN_CPU1_PHASE5
J 0
(-2515 3485);
DISPLAY 0.617021 (-2515 3485);
PAINT ORANGE (-2515 3485);
FORCEPROP 2 LASTPROP $XRERR UNIQUE?
J 0
(-2755 3485);
DISPLAY 0.638298 (-2755 3485);
PAINT MONO (-2755 3485);
DISPLAY INVISIBLE (-2755 3485);
WIRE 16 -1 (-2400 3400)(-2400 3475);
WIRE 16 -1 (-1550 3475)(-2400 3475);
WIRE 16 -1 (-1000 4125)(-1000 4025);
WIRE 16 -1 (-2750 4125)(-1000 4125);
FORCEPROP 0 LAST SIG_NAME VR_PVCCIN_CPU1_PH5_OCSET
J 0
(-2435 4135);
DISPLAY 0.617021 (-2435 4135);
PAINT ORANGE (-2435 4135);
FORCEPROP 2 LASTPROP $XRERR UNIQUE?
J 0
(-2675 4135);
DISPLAY 0.638298 (-2675 4135);
PAINT MONO (-2675 4135);
DISPLAY INVISIBLE (-2675 4135);
WIRE 16 -1 (-2750 4325)(-1200 4325);
FORCEPROP 2 LAST SIG_NAME ISENSE_PVCCIN_CPU1_PH5_IMON
J 0
(-2440 4335);
DISPLAY 0.617021 (-2440 4335);
PAINT ORANGE (-2440 4335);
WIRE 16 -1 (-5900 3575)(-5900 3550);
WIRE 16 -1 (-4900 3575)(-5900 3575);
FORCEPROP 2 LAST SIG_NAME VR_PVCCIN_CPU1_PH5_BOOT
J 0
(-5865 3585);
DISPLAY 0.617021 (-5865 3585);
PAINT ORANGE (-5865 3585);
FORCEPROP 2 LASTPROP $XRERR UNIQUE?
J 0
(-6105 3585);
DISPLAY 0.638298 (-6105 3585);
PAINT MONO (-6105 3585);
DISPLAY INVISIBLE (-6105 3585);
WIRE 16 -1 (-6175 3675)(-3750 3675);
FORCEPROP 0 LAST VOLTAGE 3.6
J 0
(-4975 3725);
DISPLAY 1.021277 (-4975 3725);
PAINT SKYBLUE (-4975 3725);
DISPLAY INVISIBLE (-4975 3725);
DOT 1 (-350 3000);
DOT 1 (-350 3475);
DOT 1 (-4800 4650);
DOT 1 (-5125 3750);
DOT 1 (-5125 4650);
DOT 1 (-2400 3150);
DOT 1 (-1200 1775);
DOT 1 (-2675 3275);
DOT 1 (-950 2250);
DOT 1 (-950 1775);
DOT 1 (-1425 2250);
DOT 1 (-600 2250);
DOT 1 (-1075 3475);
DOT 1 (-6550 4275);
DOT 1 (-6550 3750);
DOT 1 (-6225 3750);
DOT 1 (-6225 4275);
DOT 1 (-5925 3750);
DOT 1 (-5925 4275);
DOT 1 (-5625 4325);
DOT 1 (-6850 3750);
DOT 1 (-6850 4275);
DOT 1 (-2400 3475);
DOT 1 (-3875 4275);
DOT 1 (-4025 4125);
DOT 1 (-750 3475);
DOT 1 (-2675 3325);
DOT 1 (-2675 3225);
DOT 1 (-4550 4650);
DOT 1 (-6350 4275);
DOT 1 (-5925 1900);
DOT 1 (-5925 1450);
DOT 1 (-6300 1900);
DOT 1 (-6300 1450);
DOT 1 (-3950 3575);
DOT 1 (-1950 3975);
DOT 1 (-5625 3750);
FORCENOTE
ROOM=PVCCIN_CPU1_PWR_VR
(-3905 2610) 0;
DISPLAY LEFT (-3905 2610);
DISPLAY 2.446809 (-3905 2610);
PAINT PURPLE (-3905 2610);
FORCENOTE
TP FAB1 CO-LAY WITH TI PARTS 11/16
(-1600 3675) 0;
DISPLAY LEFT (-1600 3675);
DISPLAY 0.851064 (-1600 3675);
PAINT RED (-1600 3675);
FORCENOTE
TP FAB1 CHANGE PN 0310
(-5200 4225) 0;
DISPLAY LEFT (-5200 4225);
DISPLAY 1.021277 (-5200 4225);
PAINT RED (-5200 4225);
FORCENOTE
RIPPLE GUIDE= +/- 5MV
(-7825 2600) 0;
DISPLAY LEFT (-7825 2600);
DISPLAY 0.808511 (-7825 2600);
PAINT PURPLE (-7825 2600);
FORCENOTE
DC TOL = +/-17MV
(-7825 2550) 0;
DISPLAY LEFT (-7825 2550);
DISPLAY 0.808511 (-7825 2550);
PAINT PURPLE (-7825 2550);
FORCENOTE
AC + RIPPLE TOL =  +/-22MV
(-7825 2500) 0;
DISPLAY LEFT (-7825 2500);
DISPLAY 0.808511 (-7825 2500);
PAINT PURPLE (-7825 2500);
FORCENOTE
TDA21470
(-3400 4400) 0;
DISPLAY LEFT (-3400 4400);
DISPLAY 1.021277 (-3400 4400);
PAINT SKYBLUE (-3400 4400);
FORCENOTE
TP FAB1 DEL NET 0309
(-2550 4075) 0;
DISPLAY LEFT (-2550 4075);
DISPLAY 1.021277 (-2550 4075);
PAINT RED (-2550 4075);
FORCENOTE
TP FAB1 CHANGE L1C2 PN 0122
(-1600 3600) 0;
DISPLAY LEFT (-1600 3600);
DISPLAY 1.021277 (-1600 3600);
PAINT RED (-1600 3600);
FORCENOTE
TP FAB1 CHANGE TO 0 OHM 0107
(-5575 4725) 0;
DISPLAY LEFT (-5575 4725);
DISPLAY 0.638298 (-5575 4725);
PAINT RED (-5575 4725);
FORCENOTE
PLACE ON TOP
(-5330 3725) 0;
DISPLAY LEFT (-5330 3725);
DISPLAY 1.553191 (-5330 3725);
PAINT PURPLE (-5330 3725);
FORCENOTE
TP FAB1 CHANGE L1B2 PN 0122
(-3450 1925) 0;
DISPLAY LEFT (-3450 1925);
DISPLAY 1.021277 (-3450 1925);
PAINT RED (-3450 1925);
FORCENOTE
TP FAB1 CO-LAY WITH TI PARTS 11/16
(-5150 3100) 0;
DISPLAY LEFT (-5150 3100);
DISPLAY 0.851064 (-5150 3100);
PAINT RED (-5150 3100);
FORCENOTE
TP FAB1 DELETE ADM4073, CAP, RES 0321
(-1525 875) 0;
DISPLAY LEFT (-1525 875);
DISPLAY 1.021277 (-1525 875);
PAINT RED (-1525 875);
FORCENOTE
TP FAB1 CHANGE RES PN 0218
(-2100 2525) 0;
DISPLAY LEFT (-2100 2525);
DISPLAY 0.808511 (-2100 2525);
PAINT RED (-2100 2525);
FORCENOTE
ROOM = PVCCIN_CPU1_FILTER_VR
(-3690 640) 0;
DISPLAY LEFT (-3690 640);
DISPLAY 2.446809 (-3690 640);
PAINT PURPLE (-3690 640);
FORCENOTE
INPUT FILTER
(-2965 2415) 0;
DISPLAY LEFT (-2965 2415);
PAINT PURPLE (-2965 2415);
FORCENOTE
SOCKET SIDE
(-4815 1690) 0;
DISPLAY LEFT (-4815 1690);
PAINT PURPLE (-4815 1690);
FORCENOTE
ROOM = PVCCIN_CPU1_VSENSE_VR
(-7190 590) 0;
DISPLAY LEFT (-7190 590);
DISPLAY 2.446809 (-7190 590);
PAINT PURPLE (-7190 590);
FORCENOTE
PVCCIN CPU1 VOLTAGE SENSE
(-7340 1315) 0;
DISPLAY LEFT (-7340 1315);
PAINT PURPLE (-7340 1315);
FORCENOTE
ROUT AS DIFF PAIR
(-6915 1690) 0;
DISPLAY LEFT (-6915 1690);
DISPLAY 0.808511 (-6915 1690);
PAINT PURPLE (-6915 1690);
FORCENOTE
10MIL WIDTH
(-6790 1615) 0;
DISPLAY LEFT (-6790 1615);
DISPLAY 0.808511 (-6790 1615);
PAINT PURPLE (-6790 1615);
FORCENOTE
5MIL SPACING
(-6815 1540) 0;
DISPLAY LEFT (-6815 1540);
DISPLAY 0.808511 (-6815 1540);
PAINT PURPLE (-6815 1540);
FORCENOTE
VBOOT=1.7V
(-7825 2150) 0;
DISPLAY LEFT (-7825 2150);
DISPLAY 0.808511 (-7825 2150);
PAINT PURPLE (-7825 2150);
FORCENOTE
VOUT=1.8V(NOM)
(-7825 2650) 0;
DISPLAY LEFT (-7825 2650);
DISPLAY 0.808511 (-7825 2650);
PAINT PURPLE (-7825 2650);
FORCENOTE
SPOF
(-5905 3050) 0;
DISPLAY LEFT (-5905 3050);
DISPLAY 1.936170 (-5905 3050);
PAINT PURPLE (-5905 3050);
FORCENOTE
IOUT DI/DT = 778 A/US
(-7825 2300) 0;
DISPLAY LEFT (-7825 2300);
DISPLAY 0.808511 (-7825 2300);
PAINT PURPLE (-7825 2300);
FORCENOTE
IOUT STEP=187 APP
(-7825 2350) 0;
DISPLAY LEFT (-7825 2350);
DISPLAY 0.808511 (-7825 2350);
PAINT PURPLE (-7825 2350);
FORCENOTE
IOUT PK=228A
(-7825 2400) 0;
DISPLAY LEFT (-7825 2400);
DISPLAY 0.808511 (-7825 2400);
PAINT PURPLE (-7825 2400);
FORCENOTE
IOUT TDC=88A
(-7825 2450) 0;
DISPLAY LEFT (-7825 2450);
DISPLAY 0.808511 (-7825 2450);
PAINT PURPLE (-7825 2450);
FORCENOTE
LL=0.9MOHM
(-7825 2200) 0;
DISPLAY LEFT (-7825 2200);
DISPLAY 0.808511 (-7825 2200);
PAINT PURPLE (-7825 2200);
FORCENOTE
SW FREQ=625 KHZ 
(-7825 2250) 0;
DISPLAY LEFT (-7825 2250);
DISPLAY 0.808511 (-7825 2250);
PAINT PURPLE (-7825 2250);
FORCENOTE
VR CONTROLLER SIDE
(-7940 1690) 0;
DISPLAY LEFT (-7940 1690);
PAINT PURPLE (-7940 1690);
FORCENOTE
TP FAB1 CHANGE RES TO 1 OHM 0603 0107
(-1800 2800) 0;
DISPLAY LEFT (-1800 2800);
DISPLAY 0.638298 (-1800 2800);
PAINT RED (-1800 2800);
FORCENOTE
TP FAB1 CO-LAY WITH TI PARTS 11/16
(-1800 2875) 0;
DISPLAY LEFT (-1800 2875);
DISPLAY 0.680851 (-1800 2875);
PAINT RED (-1800 2875);
FORCENOTE
TP FAB1 ADD NET NAME 12/04
(-1800 3050) 0;
DISPLAY LEFT (-1800 3050);
DISPLAY 0.638298 (-1800 3050);
PAINT RED (-1800 3050);
QUIT
